FILE_TYPE = MACRO_DRAWING;
SET COLOR_WIRE YELLOW;
SET COLOR_PROP ORANGE;
SET COLOR_DOT WHITE;
SET COLOR_ARC YELLOW;
SET COLOR_BODY GREEN;
SET COLOR_NOTE PURPLE;
SET PROP_DISPLAY VALUE;
SET PAGE_NUMBER P429;
FORCEADD OFFPAGE..1
(-4400 2025);
FORCEPROP 2 LAST $XR0 309 
J 0
(-4652 2025);
DISPLAY 0.638298 (-4652 2025);
PAINT MONO (-4652 2025);
FORCEPROP 2 LAST CDS_LIB standard
J 0
(-4400 2025);
DISPLAY INVISIBLE (-4400 2025);
FORCEPROP 1 LAST OFFPAGE TRUE
J 0
(-4075 1900);
DISPLAY 0.872340 (-4075 1900);
DISPLAY INVISIBLE (-4075 1900);
FORCEPROP 1 LAST COMMENT_BODY TRUE
J 0
(-4275 1925);
DISPLAY 0.872340 (-4275 1925);
PAINT GREEN (-4275 1925);
DISPLAY INVISIBLE (-4275 1925);
FORCEPROP 2 LAST PATH I1
J 0
(-4650 2075);
DISPLAY 0.680851 (-4650 2075);
DISPLAY INVISIBLE (-4650 2075);
FORCEADD TAP..1
R 2
(-3450 1400);
FORCEPROP 3 LASTPIN (-3400 1400) SIG_NAME P5E_CPU0_P3_TX_BUF_DN<3>
J 0
(-3390 1410);
DISPLAY 0.659574 (-3390 1410);
PAINT MONO (-3390 1410);
DISPLAY INVISIBLE (-3390 1410);
FORCEPROP 1 LASTPIN (-3400 1400) BN 3
J 2
(-3388 1408);
DISPLAY 0.680851 (-3388 1408);
PAINT GREEN (-3388 1408);
FORCEPROP 2 LAST CDS_LIB standard
J 0
(-3450 1400);
DISPLAY INVISIBLE (-3450 1400);
FORCEPROP 1 LAST BODY_TYPE PLUMBING
J 2
(-3450 1450);
DISPLAY 0.872340 (-3450 1450);
PAINT GREEN (-3450 1450);
DISPLAY INVISIBLE (-3450 1450);
FORCEPROP 1 LAST HDL_TAP TRUE
J 2
(-3775 1275);
DISPLAY 0.872340 (-3775 1275);
DISPLAY INVISIBLE (-3775 1275);
FORCEPROP 1 LAST PATH I10
J 2
(-3448 1400);
DISPLAY 0.872340 (-3448 1400);
PAINT GREEN (-3448 1400);
DISPLAY INVISIBLE (-3448 1400);
FORCEADD Q_CAP_DIFFBUS..2
R 2
(-7075 1450);
FORCEPROP 1 LAST LOCATION C6619
J 2
(-6800 1450);
DISPLAY 0.723404 (-6800 1450);
PAINT GREEN (-6800 1450);
FORCEPROP 2 LAST $SEC 1
J 2
(-6900 1525);
DISPLAY 0.680851 (-6900 1525);
PAINT MONO (-6900 1525);
DISPLAY INVISIBLE (-6900 1525);
FORCEPROP 2 LAST CDS_SEC 1
J 2
(-6900 1525);
DISPLAY 0.680851 (-6900 1525);
DISPLAY INVISIBLE (-6900 1525);
FORCEPROP 2 LASTPIN (-7000 1450) $PN 1
J 0
(-6990 1460);
DISPLAY 0.808511 (-6990 1460);
FORCEPROP 2 LASTPIN (-7150 1450) $PN 2
J 2
(-7160 1460);
DISPLAY 0.808511 (-7160 1460);
FORCEPROP 2 LAST VALUE DIFF BUS_0.22UF
J 2
(-7225 1450);
DISPLAY 0.553191 (-7225 1450);
FORCEPROP 1 LAST CDS_LMAN_SYM_OUTLINE -25,50,25,-50
J 2
(-7075 1450);
DISPLAY 0.468085 (-7075 1450);
PAINT GREEN (-7075 1450);
DISPLAY INVISIBLE (-7075 1450);
FORCEPROP 2 LAST CDS_LIB pure_quanta
J 2
(-7075 1450);
DISPLAY INVISIBLE (-7075 1450);
FORCEPROP 1 LAST PIN_NAMES_ROTATE TRUE
J 2
(-7075 1450);
DISPLAY 0.489362 (-7075 1450);
PAINT GREEN (-7075 1450);
DISPLAY INVISIBLE (-7075 1450);
FORCEPROP 2 LAST VOLTAGE 6.3V
J 2
(-7425 1500);
DISPLAY 0.553191 (-7425 1500);
DISPLAY INVISIBLE (-7425 1500);
FORCEPROP 1 LAST MATERIAL X6S
J 2
(-7066 1529);
DISPLAY 0.574468 (-7066 1529);
PAINT GREEN (-7066 1529);
DISPLAY INVISIBLE (-7066 1529);
FORCEPROP 2 LAST PACK_TYPE C0201
J 2
(-7250 1500);
DISPLAY 0.553191 (-7250 1500);
DISPLAY INVISIBLE (-7250 1500);
FORCEPROP 2 LAST TOLERANCE 20%
J 2
(-7150 1500);
DISPLAY 0.553191 (-7150 1500);
DISPLAY INVISIBLE (-7150 1500);
FORCEPROP 1 LAST PATH I100
J 2
(-7075 1450);
DISPLAY 0.723404 (-7075 1450);
DISPLAY INVISIBLE (-7075 1450);
FORCEPROP 1 LAST PART_NUMBER SP_CH4221MEE01
J 2
(-7191 1538);
DISPLAY 0.574468 (-7191 1538);
PAINT GREEN (-7191 1538);
DISPLAY INVISIBLE (-7191 1538);
FORCEPROP 1 LAST LOCATION C6619
J 0
(-6825 1525);
DISPLAY 1.021277 (-6825 1525);
DISPLAY INVISIBLE (-6825 1525);
FORCEADD Q_CAP_DIFFBUS..2
R 2
(-7075 1650);
FORCEPROP 1 LAST LOCATION C6617
J 2
(-6800 1650);
DISPLAY 0.723404 (-6800 1650);
PAINT GREEN (-6800 1650);
FORCEPROP 2 LAST $SEC 1
J 2
(-6900 1725);
DISPLAY 0.680851 (-6900 1725);
PAINT MONO (-6900 1725);
DISPLAY INVISIBLE (-6900 1725);
FORCEPROP 2 LAST CDS_SEC 1
J 2
(-6900 1725);
DISPLAY 0.680851 (-6900 1725);
DISPLAY INVISIBLE (-6900 1725);
FORCEPROP 2 LASTPIN (-7000 1650) $PN 1
J 0
(-6990 1660);
DISPLAY 0.808511 (-6990 1660);
FORCEPROP 2 LASTPIN (-7150 1650) $PN 2
J 2
(-7160 1660);
DISPLAY 0.808511 (-7160 1660);
FORCEPROP 2 LAST VALUE DIFF BUS_0.22UF
J 2
(-7225 1650);
DISPLAY 0.553191 (-7225 1650);
FORCEPROP 1 LAST CDS_LMAN_SYM_OUTLINE -25,50,25,-50
J 2
(-7075 1650);
DISPLAY 0.468085 (-7075 1650);
PAINT GREEN (-7075 1650);
DISPLAY INVISIBLE (-7075 1650);
FORCEPROP 2 LAST CDS_LIB pure_quanta
J 2
(-7075 1650);
DISPLAY INVISIBLE (-7075 1650);
FORCEPROP 1 LAST PIN_NAMES_ROTATE TRUE
J 2
(-7075 1650);
DISPLAY 0.489362 (-7075 1650);
PAINT GREEN (-7075 1650);
DISPLAY INVISIBLE (-7075 1650);
FORCEPROP 2 LAST VOLTAGE 6.3V
J 2
(-7425 1700);
DISPLAY 0.553191 (-7425 1700);
DISPLAY INVISIBLE (-7425 1700);
FORCEPROP 1 LAST MATERIAL X6S
J 2
(-7066 1729);
DISPLAY 0.574468 (-7066 1729);
PAINT GREEN (-7066 1729);
DISPLAY INVISIBLE (-7066 1729);
FORCEPROP 2 LAST PACK_TYPE C0201
J 2
(-7250 1700);
DISPLAY 0.553191 (-7250 1700);
DISPLAY INVISIBLE (-7250 1700);
FORCEPROP 2 LAST TOLERANCE 20%
J 2
(-7150 1700);
DISPLAY 0.553191 (-7150 1700);
DISPLAY INVISIBLE (-7150 1700);
FORCEPROP 1 LAST PATH I101
J 2
(-7075 1650);
DISPLAY 0.723404 (-7075 1650);
DISPLAY INVISIBLE (-7075 1650);
FORCEPROP 1 LAST PART_NUMBER SP_CH4221MEE01
J 2
(-7191 1738);
DISPLAY 0.574468 (-7191 1738);
PAINT GREEN (-7191 1738);
DISPLAY INVISIBLE (-7191 1738);
FORCEPROP 1 LAST LOCATION C6617
J 0
(-6825 1725);
DISPLAY 1.021277 (-6825 1725);
DISPLAY INVISIBLE (-6825 1725);
FORCEADD Q_CAP_DIFFBUS..2
R 2
(-7075 1850);
FORCEPROP 1 LAST LOCATION C6615
J 2
(-6800 1850);
DISPLAY 0.723404 (-6800 1850);
PAINT GREEN (-6800 1850);
FORCEPROP 2 LAST $SEC 1
J 2
(-6900 1925);
DISPLAY 0.680851 (-6900 1925);
PAINT MONO (-6900 1925);
DISPLAY INVISIBLE (-6900 1925);
FORCEPROP 2 LAST CDS_SEC 1
J 2
(-6900 1925);
DISPLAY 0.680851 (-6900 1925);
DISPLAY INVISIBLE (-6900 1925);
FORCEPROP 2 LASTPIN (-7000 1850) $PN 1
J 0
(-6990 1860);
DISPLAY 0.808511 (-6990 1860);
FORCEPROP 2 LASTPIN (-7150 1850) $PN 2
J 2
(-7160 1860);
DISPLAY 0.808511 (-7160 1860);
FORCEPROP 2 LAST VALUE DIFF BUS_0.22UF
J 2
(-7225 1850);
DISPLAY 0.553191 (-7225 1850);
FORCEPROP 1 LAST CDS_LMAN_SYM_OUTLINE -25,50,25,-50
J 2
(-7075 1850);
DISPLAY 0.468085 (-7075 1850);
PAINT GREEN (-7075 1850);
DISPLAY INVISIBLE (-7075 1850);
FORCEPROP 2 LAST CDS_LIB pure_quanta
J 2
(-7075 1850);
DISPLAY INVISIBLE (-7075 1850);
FORCEPROP 1 LAST PIN_NAMES_ROTATE TRUE
J 2
(-7075 1850);
DISPLAY 0.489362 (-7075 1850);
PAINT GREEN (-7075 1850);
DISPLAY INVISIBLE (-7075 1850);
FORCEPROP 2 LAST VOLTAGE 6.3V
J 2
(-7425 1900);
DISPLAY 0.553191 (-7425 1900);
DISPLAY INVISIBLE (-7425 1900);
FORCEPROP 1 LAST MATERIAL X6S
J 2
(-7066 1929);
DISPLAY 0.574468 (-7066 1929);
PAINT GREEN (-7066 1929);
DISPLAY INVISIBLE (-7066 1929);
FORCEPROP 2 LAST PACK_TYPE C0201
J 2
(-7250 1900);
DISPLAY 0.553191 (-7250 1900);
DISPLAY INVISIBLE (-7250 1900);
FORCEPROP 2 LAST TOLERANCE 20%
J 2
(-7150 1900);
DISPLAY 0.553191 (-7150 1900);
DISPLAY INVISIBLE (-7150 1900);
FORCEPROP 1 LAST PATH I102
J 2
(-7075 1850);
DISPLAY 0.723404 (-7075 1850);
DISPLAY INVISIBLE (-7075 1850);
FORCEPROP 1 LAST PART_NUMBER SP_CH4221MEE01
J 2
(-7191 1938);
DISPLAY 0.574468 (-7191 1938);
PAINT GREEN (-7191 1938);
DISPLAY INVISIBLE (-7191 1938);
FORCEPROP 1 LAST LOCATION C6615
J 0
(-6825 1925);
DISPLAY 1.021277 (-6825 1925);
DISPLAY INVISIBLE (-6825 1925);
FORCEADD Q_CAP_DIFFBUS..2
R 2
(-7075 1800);
FORCEPROP 1 LAST LOCATION C6616
J 2
(-6800 1800);
DISPLAY 0.723404 (-6800 1800);
PAINT GREEN (-6800 1800);
FORCEPROP 2 LAST $SEC 1
J 2
(-6900 1875);
DISPLAY 0.680851 (-6900 1875);
PAINT MONO (-6900 1875);
DISPLAY INVISIBLE (-6900 1875);
FORCEPROP 2 LAST CDS_SEC 1
J 2
(-6900 1875);
DISPLAY 0.680851 (-6900 1875);
DISPLAY INVISIBLE (-6900 1875);
FORCEPROP 2 LASTPIN (-7000 1800) $PN 1
J 0
(-6990 1810);
DISPLAY 0.808511 (-6990 1810);
FORCEPROP 2 LASTPIN (-7150 1800) $PN 2
J 2
(-7160 1810);
DISPLAY 0.808511 (-7160 1810);
FORCEPROP 2 LAST VALUE DIFF BUS_0.22UF
J 2
(-7225 1800);
DISPLAY 0.553191 (-7225 1800);
FORCEPROP 1 LAST CDS_LMAN_SYM_OUTLINE -25,50,25,-50
J 2
(-7075 1800);
DISPLAY 0.468085 (-7075 1800);
PAINT GREEN (-7075 1800);
DISPLAY INVISIBLE (-7075 1800);
FORCEPROP 2 LAST CDS_LIB pure_quanta
J 2
(-7075 1800);
DISPLAY INVISIBLE (-7075 1800);
FORCEPROP 1 LAST PIN_NAMES_ROTATE TRUE
J 2
(-7075 1800);
DISPLAY 0.489362 (-7075 1800);
PAINT GREEN (-7075 1800);
DISPLAY INVISIBLE (-7075 1800);
FORCEPROP 2 LAST VOLTAGE 6.3V
J 2
(-7425 1850);
DISPLAY 0.553191 (-7425 1850);
DISPLAY INVISIBLE (-7425 1850);
FORCEPROP 1 LAST MATERIAL X6S
J 2
(-7066 1879);
DISPLAY 0.574468 (-7066 1879);
PAINT GREEN (-7066 1879);
DISPLAY INVISIBLE (-7066 1879);
FORCEPROP 2 LAST PACK_TYPE C0201
J 2
(-7250 1850);
DISPLAY 0.553191 (-7250 1850);
DISPLAY INVISIBLE (-7250 1850);
FORCEPROP 2 LAST TOLERANCE 20%
J 2
(-7150 1850);
DISPLAY 0.553191 (-7150 1850);
DISPLAY INVISIBLE (-7150 1850);
FORCEPROP 1 LAST PATH I103
J 2
(-7075 1800);
DISPLAY 0.723404 (-7075 1800);
DISPLAY INVISIBLE (-7075 1800);
FORCEPROP 1 LAST PART_NUMBER SP_CH4221MEE01
J 2
(-7191 1888);
DISPLAY 0.574468 (-7191 1888);
PAINT GREEN (-7191 1888);
DISPLAY INVISIBLE (-7191 1888);
FORCEPROP 1 LAST LOCATION C6616
J 0
(-6825 1875);
DISPLAY 1.021277 (-6825 1875);
DISPLAY INVISIBLE (-6825 1875);
FORCEADD Q_CAP_DIFFBUS..2
R 2
(-7075 2000);
FORCEPROP 1 LAST LOCATION C6614
J 2
(-6800 2000);
DISPLAY 0.723404 (-6800 2000);
PAINT GREEN (-6800 2000);
FORCEPROP 2 LAST $SEC 1
J 2
(-6900 2075);
DISPLAY 0.680851 (-6900 2075);
PAINT MONO (-6900 2075);
DISPLAY INVISIBLE (-6900 2075);
FORCEPROP 2 LAST CDS_SEC 1
J 2
(-6900 2075);
DISPLAY 0.680851 (-6900 2075);
DISPLAY INVISIBLE (-6900 2075);
FORCEPROP 2 LASTPIN (-7000 2000) $PN 1
J 0
(-6990 2010);
DISPLAY 0.808511 (-6990 2010);
FORCEPROP 2 LASTPIN (-7150 2000) $PN 2
J 2
(-7160 2010);
DISPLAY 0.808511 (-7160 2010);
FORCEPROP 2 LAST VALUE DIFF BUS_0.22UF
J 2
(-7225 2000);
DISPLAY 0.553191 (-7225 2000);
FORCEPROP 1 LAST CDS_LMAN_SYM_OUTLINE -25,50,25,-50
J 2
(-7075 2000);
DISPLAY 0.468085 (-7075 2000);
PAINT GREEN (-7075 2000);
DISPLAY INVISIBLE (-7075 2000);
FORCEPROP 2 LAST CDS_LIB pure_quanta
J 2
(-7075 2000);
DISPLAY INVISIBLE (-7075 2000);
FORCEPROP 1 LAST PIN_NAMES_ROTATE TRUE
J 2
(-7075 2000);
DISPLAY 0.489362 (-7075 2000);
PAINT GREEN (-7075 2000);
DISPLAY INVISIBLE (-7075 2000);
FORCEPROP 2 LAST VOLTAGE 6.3V
J 2
(-7425 2050);
DISPLAY 0.553191 (-7425 2050);
DISPLAY INVISIBLE (-7425 2050);
FORCEPROP 1 LAST MATERIAL X6S
J 2
(-7066 2079);
DISPLAY 0.574468 (-7066 2079);
PAINT GREEN (-7066 2079);
DISPLAY INVISIBLE (-7066 2079);
FORCEPROP 2 LAST PACK_TYPE C0201
J 2
(-7250 2050);
DISPLAY 0.553191 (-7250 2050);
DISPLAY INVISIBLE (-7250 2050);
FORCEPROP 2 LAST TOLERANCE 20%
J 2
(-7150 2050);
DISPLAY 0.553191 (-7150 2050);
DISPLAY INVISIBLE (-7150 2050);
FORCEPROP 1 LAST PATH I104
J 2
(-7075 2000);
DISPLAY 0.723404 (-7075 2000);
DISPLAY INVISIBLE (-7075 2000);
FORCEPROP 1 LAST PART_NUMBER SP_CH4221MEE01
J 2
(-7191 2088);
DISPLAY 0.574468 (-7191 2088);
PAINT GREEN (-7191 2088);
DISPLAY INVISIBLE (-7191 2088);
FORCEPROP 1 LAST LOCATION C6614
J 0
(-6825 2075);
DISPLAY 1.021277 (-6825 2075);
DISPLAY INVISIBLE (-6825 2075);
FORCEADD Q_CAP_DIFFBUS..2
R 2
(-7075 2050);
FORCEPROP 1 LAST LOCATION C6613
J 2
(-6800 2050);
DISPLAY 0.723404 (-6800 2050);
PAINT GREEN (-6800 2050);
FORCEPROP 2 LAST $SEC 1
J 2
(-6900 2125);
DISPLAY 0.680851 (-6900 2125);
PAINT MONO (-6900 2125);
DISPLAY INVISIBLE (-6900 2125);
FORCEPROP 2 LAST CDS_SEC 1
J 2
(-6900 2125);
DISPLAY 0.680851 (-6900 2125);
DISPLAY INVISIBLE (-6900 2125);
FORCEPROP 2 LASTPIN (-7000 2050) $PN 1
J 0
(-6990 2060);
DISPLAY 0.808511 (-6990 2060);
FORCEPROP 2 LASTPIN (-7150 2050) $PN 2
J 2
(-7160 2060);
DISPLAY 0.808511 (-7160 2060);
FORCEPROP 2 LAST PACK_TYPE C0201
J 2
(-7125 2200);
DISPLAY 0.553191 (-7125 2200);
PAINT GREEN (-7125 2200);
FORCEPROP 1 LAST MATERIAL X6S
J 2
(-7166 2254);
DISPLAY 0.574468 (-7166 2254);
PAINT GREEN (-7166 2254);
FORCEPROP 2 LAST TOLERANCE 20%
J 2
(-7025 2200);
DISPLAY 0.553191 (-7025 2200);
PAINT GREEN (-7025 2200);
FORCEPROP 2 LAST VALUE DIFF BUS_0.22UF
J 2
(-7225 2050);
DISPLAY 0.553191 (-7225 2050);
FORCEPROP 2 LAST VOLTAGE 6.3V
J 2
(-6900 2200);
DISPLAY 0.553191 (-6900 2200);
PAINT GREEN (-6900 2200);
FORCEPROP 2 LAST CDS_LIB pure_quanta
J 2
(-7075 2050);
DISPLAY INVISIBLE (-7075 2050);
FORCEPROP 1 LAST CDS_LMAN_SYM_OUTLINE -25,50,25,-50
J 2
(-7075 2050);
DISPLAY 0.468085 (-7075 2050);
PAINT GREEN (-7075 2050);
DISPLAY INVISIBLE (-7075 2050);
FORCEPROP 1 LAST PIN_NAMES_ROTATE TRUE
J 2
(-7075 2050);
DISPLAY 0.489362 (-7075 2050);
PAINT GREEN (-7075 2050);
DISPLAY INVISIBLE (-7075 2050);
FORCEPROP 1 LAST PATH I105
J 2
(-7075 2050);
DISPLAY 0.723404 (-7075 2050);
DISPLAY INVISIBLE (-7075 2050);
FORCEPROP 1 LAST PART_NUMBER SP_CH4221MEE01
J 2
(-6891 2138);
DISPLAY 0.574468 (-6891 2138);
PAINT GREEN (-6891 2138);
DISPLAY INVISIBLE (-6891 2138);
FORCEPROP 1 LAST LOCATION C6613
J 0
(-6825 2125);
DISPLAY 1.021277 (-6825 2125);
DISPLAY INVISIBLE (-6825 2125);
FORCEADD TAP..1
(-6325 600);
FORCEPROP 3 LASTPIN (-6375 600) SIG_NAME P5E_CPU0_P3_TX_BUF_C_DN<15>
J 0
(-6365 610);
DISPLAY 0.659574 (-6365 610);
PAINT MONO (-6365 610);
DISPLAY INVISIBLE (-6365 610);
FORCEPROP 1 LASTPIN (-6375 600) BN 15
J 0
(-6387 608);
DISPLAY 0.680851 (-6387 608);
PAINT GREEN (-6387 608);
FORCEPROP 2 LAST CDS_LIB standard
J 0
(-6325 600);
DISPLAY INVISIBLE (-6325 600);
FORCEPROP 1 LAST BODY_TYPE PLUMBING
J 0
(-6325 650);
DISPLAY 0.872340 (-6325 650);
PAINT GREEN (-6325 650);
DISPLAY INVISIBLE (-6325 650);
FORCEPROP 1 LAST HDL_TAP TRUE
J 0
(-6000 475);
DISPLAY 0.872340 (-6000 475);
DISPLAY INVISIBLE (-6000 475);
FORCEPROP 1 LAST PATH I106
J 0
(-6327 600);
DISPLAY 0.872340 (-6327 600);
PAINT GREEN (-6327 600);
DISPLAY INVISIBLE (-6327 600);
FORCEADD TAP..1
(-6525 650);
FORCEPROP 3 LASTPIN (-6575 650) SIG_NAME P5E_CPU0_P3_TX_BUF_C_DP<15>
J 0
(-6565 660);
DISPLAY 0.659574 (-6565 660);
PAINT MONO (-6565 660);
DISPLAY INVISIBLE (-6565 660);
FORCEPROP 1 LASTPIN (-6575 650) BN 15
J 0
(-6587 658);
DISPLAY 0.680851 (-6587 658);
PAINT GREEN (-6587 658);
FORCEPROP 2 LAST CDS_LIB standard
J 0
(-6525 650);
DISPLAY INVISIBLE (-6525 650);
FORCEPROP 1 LAST BODY_TYPE PLUMBING
J 0
(-6525 700);
DISPLAY 0.872340 (-6525 700);
PAINT GREEN (-6525 700);
DISPLAY INVISIBLE (-6525 700);
FORCEPROP 1 LAST HDL_TAP TRUE
J 0
(-6200 525);
DISPLAY 0.872340 (-6200 525);
DISPLAY INVISIBLE (-6200 525);
FORCEPROP 1 LAST PATH I107
J 0
(-6527 650);
DISPLAY 0.872340 (-6527 650);
PAINT GREEN (-6527 650);
DISPLAY INVISIBLE (-6527 650);
FORCEADD TAP..1
(-6525 850);
FORCEPROP 3 LASTPIN (-6575 850) SIG_NAME P5E_CPU0_P3_TX_BUF_C_DP<14>
J 0
(-6565 860);
DISPLAY 0.659574 (-6565 860);
PAINT MONO (-6565 860);
DISPLAY INVISIBLE (-6565 860);
FORCEPROP 1 LASTPIN (-6575 850) BN 14
J 0
(-6587 858);
DISPLAY 0.680851 (-6587 858);
PAINT GREEN (-6587 858);
FORCEPROP 2 LAST CDS_LIB standard
J 0
(-6525 850);
DISPLAY INVISIBLE (-6525 850);
FORCEPROP 1 LAST BODY_TYPE PLUMBING
J 0
(-6525 900);
DISPLAY 0.872340 (-6525 900);
PAINT GREEN (-6525 900);
DISPLAY INVISIBLE (-6525 900);
FORCEPROP 1 LAST HDL_TAP TRUE
J 0
(-6200 725);
DISPLAY 0.872340 (-6200 725);
DISPLAY INVISIBLE (-6200 725);
FORCEPROP 1 LAST PATH I108
J 0
(-6527 850);
DISPLAY 0.872340 (-6527 850);
PAINT GREEN (-6527 850);
DISPLAY INVISIBLE (-6527 850);
FORCEADD TAP..1
(-6525 1050);
FORCEPROP 3 LASTPIN (-6575 1050) SIG_NAME P5E_CPU0_P3_TX_BUF_C_DP<13>
J 0
(-6565 1060);
DISPLAY 0.659574 (-6565 1060);
PAINT MONO (-6565 1060);
DISPLAY INVISIBLE (-6565 1060);
FORCEPROP 1 LASTPIN (-6575 1050) BN 13
J 0
(-6587 1058);
DISPLAY 0.680851 (-6587 1058);
PAINT GREEN (-6587 1058);
FORCEPROP 2 LAST CDS_LIB standard
J 0
(-6525 1050);
DISPLAY INVISIBLE (-6525 1050);
FORCEPROP 1 LAST BODY_TYPE PLUMBING
J 0
(-6525 1100);
DISPLAY 0.872340 (-6525 1100);
PAINT GREEN (-6525 1100);
DISPLAY INVISIBLE (-6525 1100);
FORCEPROP 1 LAST HDL_TAP TRUE
J 0
(-6200 925);
DISPLAY 0.872340 (-6200 925);
DISPLAY INVISIBLE (-6200 925);
FORCEPROP 1 LAST PATH I109
J 0
(-6527 1050);
DISPLAY 0.872340 (-6527 1050);
PAINT GREEN (-6527 1050);
DISPLAY INVISIBLE (-6527 1050);
FORCEADD TAP..1
R 2
(-3200 1250);
FORCEPROP 3 LASTPIN (-3150 1250) SIG_NAME P5E_CPU0_P3_TX_BUF_DP<4>
J 0
(-3140 1260);
DISPLAY 0.659574 (-3140 1260);
PAINT MONO (-3140 1260);
DISPLAY INVISIBLE (-3140 1260);
FORCEPROP 1 LASTPIN (-3150 1250) BN 4
J 2
(-3138 1258);
DISPLAY 0.680851 (-3138 1258);
PAINT GREEN (-3138 1258);
FORCEPROP 2 LAST CDS_LIB standard
J 0
(-3200 1250);
DISPLAY INVISIBLE (-3200 1250);
FORCEPROP 1 LAST BODY_TYPE PLUMBING
J 2
(-3200 1300);
DISPLAY 0.872340 (-3200 1300);
PAINT GREEN (-3200 1300);
DISPLAY INVISIBLE (-3200 1300);
FORCEPROP 1 LAST HDL_TAP TRUE
J 2
(-3525 1125);
DISPLAY 0.872340 (-3525 1125);
DISPLAY INVISIBLE (-3525 1125);
FORCEPROP 1 LAST PATH I11
J 2
(-3198 1250);
DISPLAY 0.872340 (-3198 1250);
PAINT GREEN (-3198 1250);
DISPLAY INVISIBLE (-3198 1250);
FORCEADD TAP..1
(-6325 800);
FORCEPROP 3 LASTPIN (-6375 800) SIG_NAME P5E_CPU0_P3_TX_BUF_C_DN<14>
J 0
(-6365 810);
DISPLAY 0.659574 (-6365 810);
PAINT MONO (-6365 810);
DISPLAY INVISIBLE (-6365 810);
FORCEPROP 1 LASTPIN (-6375 800) BN 14
J 0
(-6387 808);
DISPLAY 0.680851 (-6387 808);
PAINT GREEN (-6387 808);
FORCEPROP 2 LAST CDS_LIB standard
J 0
(-6325 800);
DISPLAY INVISIBLE (-6325 800);
FORCEPROP 1 LAST BODY_TYPE PLUMBING
J 0
(-6325 850);
DISPLAY 0.872340 (-6325 850);
PAINT GREEN (-6325 850);
DISPLAY INVISIBLE (-6325 850);
FORCEPROP 1 LAST HDL_TAP TRUE
J 0
(-6000 675);
DISPLAY 0.872340 (-6000 675);
DISPLAY INVISIBLE (-6000 675);
FORCEPROP 1 LAST PATH I110
J 0
(-6327 800);
DISPLAY 0.872340 (-6327 800);
PAINT GREEN (-6327 800);
DISPLAY INVISIBLE (-6327 800);
FORCEADD TAP..1
(-6325 1000);
FORCEPROP 3 LASTPIN (-6375 1000) SIG_NAME P5E_CPU0_P3_TX_BUF_C_DN<13>
J 0
(-6365 1010);
DISPLAY 0.659574 (-6365 1010);
PAINT MONO (-6365 1010);
DISPLAY INVISIBLE (-6365 1010);
FORCEPROP 1 LASTPIN (-6375 1000) BN 13
J 0
(-6387 1008);
DISPLAY 0.680851 (-6387 1008);
PAINT GREEN (-6387 1008);
FORCEPROP 2 LAST CDS_LIB standard
J 0
(-6325 1000);
DISPLAY INVISIBLE (-6325 1000);
FORCEPROP 1 LAST BODY_TYPE PLUMBING
J 0
(-6325 1050);
DISPLAY 0.872340 (-6325 1050);
PAINT GREEN (-6325 1050);
DISPLAY INVISIBLE (-6325 1050);
FORCEPROP 1 LAST HDL_TAP TRUE
J 0
(-6000 875);
DISPLAY 0.872340 (-6000 875);
DISPLAY INVISIBLE (-6000 875);
FORCEPROP 1 LAST PATH I111
J 0
(-6327 1000);
DISPLAY 0.872340 (-6327 1000);
PAINT GREEN (-6327 1000);
DISPLAY INVISIBLE (-6327 1000);
FORCEADD TAP..1
(-6525 1250);
FORCEPROP 3 LASTPIN (-6575 1250) SIG_NAME P5E_CPU0_P3_TX_BUF_C_DP<12>
J 0
(-6565 1260);
DISPLAY 0.659574 (-6565 1260);
PAINT MONO (-6565 1260);
DISPLAY INVISIBLE (-6565 1260);
FORCEPROP 1 LASTPIN (-6575 1250) BN 12
J 0
(-6587 1258);
DISPLAY 0.680851 (-6587 1258);
PAINT GREEN (-6587 1258);
FORCEPROP 2 LAST CDS_LIB standard
J 0
(-6525 1250);
DISPLAY INVISIBLE (-6525 1250);
FORCEPROP 1 LAST BODY_TYPE PLUMBING
J 0
(-6525 1300);
DISPLAY 0.872340 (-6525 1300);
PAINT GREEN (-6525 1300);
DISPLAY INVISIBLE (-6525 1300);
FORCEPROP 1 LAST HDL_TAP TRUE
J 0
(-6200 1125);
DISPLAY 0.872340 (-6200 1125);
DISPLAY INVISIBLE (-6200 1125);
FORCEPROP 1 LAST PATH I112
J 0
(-6527 1250);
DISPLAY 0.872340 (-6527 1250);
PAINT GREEN (-6527 1250);
DISPLAY INVISIBLE (-6527 1250);
FORCEADD TAP..1
(-6525 1450);
FORCEPROP 3 LASTPIN (-6575 1450) SIG_NAME P5E_CPU0_P3_TX_BUF_C_DP<11>
J 0
(-6565 1460);
DISPLAY 0.659574 (-6565 1460);
PAINT MONO (-6565 1460);
DISPLAY INVISIBLE (-6565 1460);
FORCEPROP 1 LASTPIN (-6575 1450) BN 11
J 0
(-6587 1458);
DISPLAY 0.680851 (-6587 1458);
PAINT GREEN (-6587 1458);
FORCEPROP 2 LAST CDS_LIB standard
J 0
(-6525 1450);
DISPLAY INVISIBLE (-6525 1450);
FORCEPROP 1 LAST BODY_TYPE PLUMBING
J 0
(-6525 1500);
DISPLAY 0.872340 (-6525 1500);
PAINT GREEN (-6525 1500);
DISPLAY INVISIBLE (-6525 1500);
FORCEPROP 1 LAST HDL_TAP TRUE
J 0
(-6200 1325);
DISPLAY 0.872340 (-6200 1325);
DISPLAY INVISIBLE (-6200 1325);
FORCEPROP 1 LAST PATH I113
J 0
(-6527 1450);
DISPLAY 0.872340 (-6527 1450);
PAINT GREEN (-6527 1450);
DISPLAY INVISIBLE (-6527 1450);
FORCEADD TAP..1
(-6325 1200);
FORCEPROP 3 LASTPIN (-6375 1200) SIG_NAME P5E_CPU0_P3_TX_BUF_C_DN<12>
J 0
(-6365 1210);
DISPLAY 0.659574 (-6365 1210);
PAINT MONO (-6365 1210);
DISPLAY INVISIBLE (-6365 1210);
FORCEPROP 1 LASTPIN (-6375 1200) BN 12
J 0
(-6387 1208);
DISPLAY 0.680851 (-6387 1208);
PAINT GREEN (-6387 1208);
FORCEPROP 2 LAST CDS_LIB standard
J 0
(-6325 1200);
DISPLAY INVISIBLE (-6325 1200);
FORCEPROP 1 LAST BODY_TYPE PLUMBING
J 0
(-6325 1250);
DISPLAY 0.872340 (-6325 1250);
PAINT GREEN (-6325 1250);
DISPLAY INVISIBLE (-6325 1250);
FORCEPROP 1 LAST HDL_TAP TRUE
J 0
(-6000 1075);
DISPLAY 0.872340 (-6000 1075);
DISPLAY INVISIBLE (-6000 1075);
FORCEPROP 1 LAST PATH I114
J 0
(-6327 1200);
DISPLAY 0.872340 (-6327 1200);
PAINT GREEN (-6327 1200);
DISPLAY INVISIBLE (-6327 1200);
FORCEADD TAP..1
(-6325 1600);
FORCEPROP 3 LASTPIN (-6375 1600) SIG_NAME P5E_CPU0_P3_TX_BUF_C_DN<10>
J 0
(-6365 1610);
DISPLAY 0.659574 (-6365 1610);
PAINT MONO (-6365 1610);
DISPLAY INVISIBLE (-6365 1610);
FORCEPROP 1 LASTPIN (-6375 1600) BN 10
J 0
(-6387 1608);
DISPLAY 0.680851 (-6387 1608);
PAINT GREEN (-6387 1608);
FORCEPROP 2 LAST CDS_LIB standard
J 0
(-6325 1600);
DISPLAY INVISIBLE (-6325 1600);
FORCEPROP 1 LAST BODY_TYPE PLUMBING
J 0
(-6325 1650);
DISPLAY 0.872340 (-6325 1650);
PAINT GREEN (-6325 1650);
DISPLAY INVISIBLE (-6325 1650);
FORCEPROP 1 LAST HDL_TAP TRUE
J 0
(-6000 1475);
DISPLAY 0.872340 (-6000 1475);
DISPLAY INVISIBLE (-6000 1475);
FORCEPROP 1 LAST PATH I115
J 0
(-6327 1600);
DISPLAY 0.872340 (-6327 1600);
PAINT GREEN (-6327 1600);
DISPLAY INVISIBLE (-6327 1600);
FORCEADD TAP..1
(-6325 1400);
FORCEPROP 3 LASTPIN (-6375 1400) SIG_NAME P5E_CPU0_P3_TX_BUF_C_DN<11>
J 0
(-6365 1410);
DISPLAY 0.659574 (-6365 1410);
PAINT MONO (-6365 1410);
DISPLAY INVISIBLE (-6365 1410);
FORCEPROP 1 LASTPIN (-6375 1400) BN 11
J 0
(-6387 1408);
DISPLAY 0.680851 (-6387 1408);
PAINT GREEN (-6387 1408);
FORCEPROP 2 LAST CDS_LIB standard
J 0
(-6325 1400);
DISPLAY INVISIBLE (-6325 1400);
FORCEPROP 1 LAST BODY_TYPE PLUMBING
J 0
(-6325 1450);
DISPLAY 0.872340 (-6325 1450);
PAINT GREEN (-6325 1450);
DISPLAY INVISIBLE (-6325 1450);
FORCEPROP 1 LAST HDL_TAP TRUE
J 0
(-6000 1275);
DISPLAY 0.872340 (-6000 1275);
DISPLAY INVISIBLE (-6000 1275);
FORCEPROP 1 LAST PATH I116
J 0
(-6327 1400);
DISPLAY 0.872340 (-6327 1400);
PAINT GREEN (-6327 1400);
DISPLAY INVISIBLE (-6327 1400);
FORCEADD TAP..1
(-6525 1650);
FORCEPROP 3 LASTPIN (-6575 1650) SIG_NAME P5E_CPU0_P3_TX_BUF_C_DP<10>
J 0
(-6565 1660);
DISPLAY 0.659574 (-6565 1660);
PAINT MONO (-6565 1660);
DISPLAY INVISIBLE (-6565 1660);
FORCEPROP 1 LASTPIN (-6575 1650) BN 10
J 0
(-6587 1658);
DISPLAY 0.680851 (-6587 1658);
PAINT GREEN (-6587 1658);
FORCEPROP 2 LAST CDS_LIB standard
J 0
(-6525 1650);
DISPLAY INVISIBLE (-6525 1650);
FORCEPROP 1 LAST BODY_TYPE PLUMBING
J 0
(-6525 1700);
DISPLAY 0.872340 (-6525 1700);
PAINT GREEN (-6525 1700);
DISPLAY INVISIBLE (-6525 1700);
FORCEPROP 1 LAST HDL_TAP TRUE
J 0
(-6200 1525);
DISPLAY 0.872340 (-6200 1525);
DISPLAY INVISIBLE (-6200 1525);
FORCEPROP 1 LAST PATH I117
J 0
(-6527 1650);
DISPLAY 0.872340 (-6527 1650);
PAINT GREEN (-6527 1650);
DISPLAY INVISIBLE (-6527 1650);
FORCEADD TAP..1
(-6525 1850);
FORCEPROP 3 LASTPIN (-6575 1850) SIG_NAME P5E_CPU0_P3_TX_BUF_C_DP<9>
J 0
(-6565 1860);
DISPLAY 0.659574 (-6565 1860);
PAINT MONO (-6565 1860);
DISPLAY INVISIBLE (-6565 1860);
FORCEPROP 1 LASTPIN (-6575 1850) BN 9
J 0
(-6587 1858);
DISPLAY 0.680851 (-6587 1858);
PAINT GREEN (-6587 1858);
FORCEPROP 2 LAST CDS_LIB standard
J 0
(-6525 1850);
DISPLAY INVISIBLE (-6525 1850);
FORCEPROP 1 LAST BODY_TYPE PLUMBING
J 0
(-6525 1900);
DISPLAY 0.872340 (-6525 1900);
PAINT GREEN (-6525 1900);
DISPLAY INVISIBLE (-6525 1900);
FORCEPROP 1 LAST HDL_TAP TRUE
J 0
(-6200 1725);
DISPLAY 0.872340 (-6200 1725);
DISPLAY INVISIBLE (-6200 1725);
FORCEPROP 1 LAST PATH I118
J 0
(-6527 1850);
DISPLAY 0.872340 (-6527 1850);
PAINT GREEN (-6527 1850);
DISPLAY INVISIBLE (-6527 1850);
FORCEADD TAP..1
(-6525 2050);
FORCEPROP 3 LASTPIN (-6575 2050) SIG_NAME P5E_CPU0_P3_TX_BUF_C_DP<8>
J 0
(-6565 2060);
DISPLAY 0.659574 (-6565 2060);
PAINT MONO (-6565 2060);
DISPLAY INVISIBLE (-6565 2060);
FORCEPROP 1 LASTPIN (-6575 2050) BN 8
J 0
(-6587 2058);
DISPLAY 0.680851 (-6587 2058);
PAINT GREEN (-6587 2058);
FORCEPROP 2 LAST CDS_LIB standard
J 0
(-6525 2050);
DISPLAY INVISIBLE (-6525 2050);
FORCEPROP 1 LAST BODY_TYPE PLUMBING
J 0
(-6525 2100);
DISPLAY 0.872340 (-6525 2100);
PAINT GREEN (-6525 2100);
DISPLAY INVISIBLE (-6525 2100);
FORCEPROP 1 LAST HDL_TAP TRUE
J 0
(-6200 1925);
DISPLAY 0.872340 (-6200 1925);
DISPLAY INVISIBLE (-6200 1925);
FORCEPROP 1 LAST PATH I119
J 0
(-6527 2050);
DISPLAY 0.872340 (-6527 2050);
PAINT GREEN (-6527 2050);
DISPLAY INVISIBLE (-6527 2050);
FORCEADD TAP..1
R 2
(-3200 1450);
FORCEPROP 3 LASTPIN (-3150 1450) SIG_NAME P5E_CPU0_P3_TX_BUF_DP<3>
J 0
(-3140 1460);
DISPLAY 0.659574 (-3140 1460);
PAINT MONO (-3140 1460);
DISPLAY INVISIBLE (-3140 1460);
FORCEPROP 1 LASTPIN (-3150 1450) BN 3
J 2
(-3138 1458);
DISPLAY 0.680851 (-3138 1458);
PAINT GREEN (-3138 1458);
FORCEPROP 2 LAST CDS_LIB standard
J 0
(-3200 1450);
DISPLAY INVISIBLE (-3200 1450);
FORCEPROP 1 LAST BODY_TYPE PLUMBING
J 2
(-3200 1500);
DISPLAY 0.872340 (-3200 1500);
PAINT GREEN (-3200 1500);
DISPLAY INVISIBLE (-3200 1500);
FORCEPROP 1 LAST HDL_TAP TRUE
J 2
(-3525 1325);
DISPLAY 0.872340 (-3525 1325);
DISPLAY INVISIBLE (-3525 1325);
FORCEPROP 1 LAST PATH I12
J 2
(-3198 1450);
DISPLAY 0.872340 (-3198 1450);
PAINT GREEN (-3198 1450);
DISPLAY INVISIBLE (-3198 1450);
FORCEADD TAP..1
(-6325 1800);
FORCEPROP 3 LASTPIN (-6375 1800) SIG_NAME P5E_CPU0_P3_TX_BUF_C_DN<9>
J 0
(-6365 1810);
DISPLAY 0.659574 (-6365 1810);
PAINT MONO (-6365 1810);
DISPLAY INVISIBLE (-6365 1810);
FORCEPROP 1 LASTPIN (-6375 1800) BN 9
J 0
(-6387 1808);
DISPLAY 0.680851 (-6387 1808);
PAINT GREEN (-6387 1808);
FORCEPROP 2 LAST CDS_LIB standard
J 0
(-6325 1800);
DISPLAY INVISIBLE (-6325 1800);
FORCEPROP 1 LAST BODY_TYPE PLUMBING
J 0
(-6325 1850);
DISPLAY 0.872340 (-6325 1850);
PAINT GREEN (-6325 1850);
DISPLAY INVISIBLE (-6325 1850);
FORCEPROP 1 LAST HDL_TAP TRUE
J 0
(-6000 1675);
DISPLAY 0.872340 (-6000 1675);
DISPLAY INVISIBLE (-6000 1675);
FORCEPROP 1 LAST PATH I120
J 0
(-6327 1800);
DISPLAY 0.872340 (-6327 1800);
PAINT GREEN (-6327 1800);
DISPLAY INVISIBLE (-6327 1800);
FORCEADD TAP..1
(-6325 2000);
FORCEPROP 3 LASTPIN (-6375 2000) SIG_NAME P5E_CPU0_P3_TX_BUF_C_DN<8>
J 0
(-6365 2010);
DISPLAY 0.659574 (-6365 2010);
PAINT MONO (-6365 2010);
DISPLAY INVISIBLE (-6365 2010);
FORCEPROP 1 LASTPIN (-6375 2000) BN 8
J 0
(-6387 2008);
DISPLAY 0.680851 (-6387 2008);
PAINT GREEN (-6387 2008);
FORCEPROP 2 LAST CDS_LIB standard
J 0
(-6325 2000);
DISPLAY INVISIBLE (-6325 2000);
FORCEPROP 1 LAST BODY_TYPE PLUMBING
J 0
(-6325 2050);
DISPLAY 0.872340 (-6325 2050);
PAINT GREEN (-6325 2050);
DISPLAY INVISIBLE (-6325 2050);
FORCEPROP 1 LAST HDL_TAP TRUE
J 0
(-6000 1875);
DISPLAY 0.872340 (-6000 1875);
DISPLAY INVISIBLE (-6000 1875);
FORCEPROP 1 LAST PATH I121
J 0
(-6327 2000);
DISPLAY 0.872340 (-6327 2000);
PAINT GREEN (-6327 2000);
DISPLAY INVISIBLE (-6327 2000);
FORCEADD OFFPAGE..2
(-5325 2025);
FORCEPROP 2 LAST $XR0 115 
J 0
(-5136 2025);
DISPLAY 0.638298 (-5136 2025);
PAINT MONO (-5136 2025);
FORCEPROP 2 LAST CDS_LIB standard
J 0
(-5325 2025);
DISPLAY INVISIBLE (-5325 2025);
FORCEPROP 1 LAST OFFPAGE TRUE
J 0
(-5000 1900);
DISPLAY 0.872340 (-5000 1900);
DISPLAY INVISIBLE (-5000 1900);
FORCEPROP 1 LAST COMMENT_BODY TRUE
J 0
(-5370 1930);
DISPLAY 0.872340 (-5370 1930);
PAINT GREEN (-5370 1930);
DISPLAY INVISIBLE (-5370 1930);
FORCEPROP 2 LAST PATH I122
J 0
(-5125 2075);
DISPLAY 0.680851 (-5125 2075);
DISPLAY INVISIBLE (-5125 2075);
FORCEADD OFFPAGE..2
(-5325 2075);
FORCEPROP 2 LAST $XR0 115 
J 0
(-5136 2075);
DISPLAY 0.638298 (-5136 2075);
PAINT MONO (-5136 2075);
FORCEPROP 2 LAST CDS_LIB standard
J 0
(-5325 2075);
DISPLAY INVISIBLE (-5325 2075);
FORCEPROP 1 LAST OFFPAGE TRUE
J 0
(-5000 1950);
DISPLAY 0.872340 (-5000 1950);
DISPLAY INVISIBLE (-5000 1950);
FORCEPROP 1 LAST COMMENT_BODY TRUE
J 0
(-5370 1980);
DISPLAY 0.872340 (-5370 1980);
PAINT GREEN (-5370 1980);
DISPLAY INVISIBLE (-5370 1980);
FORCEPROP 2 LAST PATH I123
J 0
(-5125 2125);
DISPLAY 0.680851 (-5125 2125);
DISPLAY INVISIBLE (-5125 2125);
FORCEADD TAP..1
(-1675 3200);
FORCEPROP 3 LASTPIN (-1725 3200) SIG_NAME P5E_CPU0_P3_TX_BUF_DN<0>
J 0
(-1715 3210);
DISPLAY 0.659574 (-1715 3210);
PAINT MONO (-1715 3210);
DISPLAY INVISIBLE (-1715 3210);
FORCEPROP 1 LASTPIN (-1725 3200) BN 0
J 0
(-1737 3208);
DISPLAY 0.680851 (-1737 3208);
PAINT GREEN (-1737 3208);
FORCEPROP 2 LAST CDS_LIB standard
J 0
(-1675 3200);
DISPLAY INVISIBLE (-1675 3200);
FORCEPROP 1 LAST BODY_TYPE PLUMBING
J 0
(-1675 3250);
DISPLAY 0.872340 (-1675 3250);
PAINT GREEN (-1675 3250);
DISPLAY INVISIBLE (-1675 3250);
FORCEPROP 1 LAST HDL_TAP TRUE
J 0
(-1350 3075);
DISPLAY 0.872340 (-1350 3075);
DISPLAY INVISIBLE (-1350 3075);
FORCEPROP 1 LAST PATH I124
J 0
(-1677 3200);
DISPLAY 0.872340 (-1677 3200);
PAINT GREEN (-1677 3200);
DISPLAY INVISIBLE (-1677 3200);
FORCEADD TAP..1
(-1875 3300);
FORCEPROP 3 LASTPIN (-1925 3300) SIG_NAME P5E_CPU0_P3_TX_BUF_DP<0>
J 0
(-1915 3310);
DISPLAY 0.659574 (-1915 3310);
PAINT MONO (-1915 3310);
DISPLAY INVISIBLE (-1915 3310);
FORCEPROP 1 LASTPIN (-1925 3300) BN 0
J 0
(-1937 3308);
DISPLAY 0.680851 (-1937 3308);
PAINT GREEN (-1937 3308);
FORCEPROP 2 LAST CDS_LIB standard
J 0
(-1875 3300);
DISPLAY INVISIBLE (-1875 3300);
FORCEPROP 1 LAST BODY_TYPE PLUMBING
J 0
(-1875 3350);
DISPLAY 0.872340 (-1875 3350);
PAINT GREEN (-1875 3350);
DISPLAY INVISIBLE (-1875 3350);
FORCEPROP 1 LAST HDL_TAP TRUE
J 0
(-1550 3175);
DISPLAY 0.872340 (-1550 3175);
DISPLAY INVISIBLE (-1550 3175);
FORCEPROP 1 LAST PATH I125
J 0
(-1877 3300);
DISPLAY 0.872340 (-1877 3300);
PAINT GREEN (-1877 3300);
DISPLAY INVISIBLE (-1877 3300);
FORCEADD TAP..1
(-1875 3650);
FORCEPROP 3 LASTPIN (-1925 3650) SIG_NAME P5E_CPU0_P3_TX_BUF_DP<1>
J 0
(-1915 3660);
DISPLAY 0.659574 (-1915 3660);
PAINT MONO (-1915 3660);
DISPLAY INVISIBLE (-1915 3660);
FORCEPROP 1 LASTPIN (-1925 3650) BN 1
J 0
(-1937 3658);
DISPLAY 0.680851 (-1937 3658);
PAINT GREEN (-1937 3658);
FORCEPROP 2 LAST CDS_LIB standard
J 0
(-1875 3650);
DISPLAY INVISIBLE (-1875 3650);
FORCEPROP 1 LAST BODY_TYPE PLUMBING
J 0
(-1875 3700);
DISPLAY 0.872340 (-1875 3700);
PAINT GREEN (-1875 3700);
DISPLAY INVISIBLE (-1875 3700);
FORCEPROP 1 LAST HDL_TAP TRUE
J 0
(-1550 3525);
DISPLAY 0.872340 (-1550 3525);
DISPLAY INVISIBLE (-1550 3525);
FORCEPROP 1 LAST PATH I126
J 0
(-1877 3650);
DISPLAY 0.872340 (-1877 3650);
PAINT GREEN (-1877 3650);
DISPLAY INVISIBLE (-1877 3650);
FORCEADD TAP..1
(-1675 3550);
FORCEPROP 3 LASTPIN (-1725 3550) SIG_NAME P5E_CPU0_P3_TX_BUF_DN<1>
J 0
(-1715 3560);
DISPLAY 0.659574 (-1715 3560);
PAINT MONO (-1715 3560);
DISPLAY INVISIBLE (-1715 3560);
FORCEPROP 1 LASTPIN (-1725 3550) BN 1
J 0
(-1737 3558);
DISPLAY 0.680851 (-1737 3558);
PAINT GREEN (-1737 3558);
FORCEPROP 2 LAST CDS_LIB standard
J 0
(-1675 3550);
DISPLAY INVISIBLE (-1675 3550);
FORCEPROP 1 LAST BODY_TYPE PLUMBING
J 0
(-1675 3600);
DISPLAY 0.872340 (-1675 3600);
PAINT GREEN (-1675 3600);
DISPLAY INVISIBLE (-1675 3600);
FORCEPROP 1 LAST HDL_TAP TRUE
J 0
(-1350 3425);
DISPLAY 0.872340 (-1350 3425);
DISPLAY INVISIBLE (-1350 3425);
FORCEPROP 1 LAST PATH I127
J 0
(-1677 3550);
DISPLAY 0.872340 (-1677 3550);
PAINT GREEN (-1677 3550);
DISPLAY INVISIBLE (-1677 3550);
FORCEADD TAP..1
(-1875 4350);
FORCEPROP 3 LASTPIN (-1925 4350) SIG_NAME P5E_CPU0_P3_TX_BUF_DP<3>
J 0
(-1915 4360);
DISPLAY 0.659574 (-1915 4360);
PAINT MONO (-1915 4360);
DISPLAY INVISIBLE (-1915 4360);
FORCEPROP 1 LASTPIN (-1925 4350) BN 3
J 0
(-1937 4358);
DISPLAY 0.680851 (-1937 4358);
PAINT GREEN (-1937 4358);
FORCEPROP 2 LAST CDS_LIB standard
J 0
(-1875 4350);
DISPLAY INVISIBLE (-1875 4350);
FORCEPROP 1 LAST BODY_TYPE PLUMBING
J 0
(-1875 4400);
DISPLAY 0.872340 (-1875 4400);
PAINT GREEN (-1875 4400);
DISPLAY INVISIBLE (-1875 4400);
FORCEPROP 1 LAST HDL_TAP TRUE
J 0
(-1550 4225);
DISPLAY 0.872340 (-1550 4225);
DISPLAY INVISIBLE (-1550 4225);
FORCEPROP 1 LAST PATH I128
J 0
(-1877 4350);
DISPLAY 0.872340 (-1877 4350);
PAINT GREEN (-1877 4350);
DISPLAY INVISIBLE (-1877 4350);
FORCEADD TAP..1
(-1875 4700);
FORCEPROP 3 LASTPIN (-1925 4700) SIG_NAME P5E_CPU0_P3_TX_BUF_DP<4>
J 0
(-1915 4710);
DISPLAY 0.659574 (-1915 4710);
PAINT MONO (-1915 4710);
DISPLAY INVISIBLE (-1915 4710);
FORCEPROP 1 LASTPIN (-1925 4700) BN 4
J 0
(-1937 4708);
DISPLAY 0.680851 (-1937 4708);
PAINT GREEN (-1937 4708);
FORCEPROP 2 LAST CDS_LIB standard
J 0
(-1875 4700);
DISPLAY INVISIBLE (-1875 4700);
FORCEPROP 1 LAST BODY_TYPE PLUMBING
J 0
(-1875 4750);
DISPLAY 0.872340 (-1875 4750);
PAINT GREEN (-1875 4750);
DISPLAY INVISIBLE (-1875 4750);
FORCEPROP 1 LAST HDL_TAP TRUE
J 0
(-1550 4575);
DISPLAY 0.872340 (-1550 4575);
DISPLAY INVISIBLE (-1550 4575);
FORCEPROP 1 LAST PATH I129
J 0
(-1877 4700);
DISPLAY 0.872340 (-1877 4700);
PAINT GREEN (-1877 4700);
DISPLAY INVISIBLE (-1877 4700);
FORCEADD TAP..1
R 2
(-3450 1800);
FORCEPROP 3 LASTPIN (-3400 1800) SIG_NAME P5E_CPU0_P3_TX_BUF_DN<1>
J 0
(-3390 1810);
DISPLAY 0.659574 (-3390 1810);
PAINT MONO (-3390 1810);
DISPLAY INVISIBLE (-3390 1810);
FORCEPROP 1 LASTPIN (-3400 1800) BN 1
J 2
(-3388 1808);
DISPLAY 0.680851 (-3388 1808);
PAINT GREEN (-3388 1808);
FORCEPROP 2 LAST CDS_LIB standard
J 0
(-3450 1800);
DISPLAY INVISIBLE (-3450 1800);
FORCEPROP 1 LAST BODY_TYPE PLUMBING
J 2
(-3450 1850);
DISPLAY 0.872340 (-3450 1850);
PAINT GREEN (-3450 1850);
DISPLAY INVISIBLE (-3450 1850);
FORCEPROP 1 LAST HDL_TAP TRUE
J 2
(-3775 1675);
DISPLAY 0.872340 (-3775 1675);
DISPLAY INVISIBLE (-3775 1675);
FORCEPROP 1 LAST PATH I13
J 2
(-3448 1800);
DISPLAY 0.872340 (-3448 1800);
PAINT GREEN (-3448 1800);
DISPLAY INVISIBLE (-3448 1800);
FORCEADD TAP..1
(-1675 4250);
FORCEPROP 3 LASTPIN (-1725 4250) SIG_NAME P5E_CPU0_P3_TX_BUF_DN<3>
J 0
(-1715 4260);
DISPLAY 0.659574 (-1715 4260);
PAINT MONO (-1715 4260);
DISPLAY INVISIBLE (-1715 4260);
FORCEPROP 1 LASTPIN (-1725 4250) BN 3
J 0
(-1737 4258);
DISPLAY 0.680851 (-1737 4258);
PAINT GREEN (-1737 4258);
FORCEPROP 2 LAST CDS_LIB standard
J 0
(-1675 4250);
DISPLAY INVISIBLE (-1675 4250);
FORCEPROP 1 LAST BODY_TYPE PLUMBING
J 0
(-1675 4300);
DISPLAY 0.872340 (-1675 4300);
PAINT GREEN (-1675 4300);
DISPLAY INVISIBLE (-1675 4300);
FORCEPROP 1 LAST HDL_TAP TRUE
J 0
(-1350 4125);
DISPLAY 0.872340 (-1350 4125);
DISPLAY INVISIBLE (-1350 4125);
FORCEPROP 1 LAST PATH I130
J 0
(-1677 4250);
DISPLAY 0.872340 (-1677 4250);
PAINT GREEN (-1677 4250);
DISPLAY INVISIBLE (-1677 4250);
FORCEADD TAP..1
(-1675 4600);
FORCEPROP 3 LASTPIN (-1725 4600) SIG_NAME P5E_CPU0_P3_TX_BUF_DN<4>
J 0
(-1715 4610);
DISPLAY 0.659574 (-1715 4610);
PAINT MONO (-1715 4610);
DISPLAY INVISIBLE (-1715 4610);
FORCEPROP 1 LASTPIN (-1725 4600) BN 4
J 0
(-1737 4608);
DISPLAY 0.680851 (-1737 4608);
PAINT GREEN (-1737 4608);
FORCEPROP 2 LAST CDS_LIB standard
J 0
(-1675 4600);
DISPLAY INVISIBLE (-1675 4600);
FORCEPROP 1 LAST BODY_TYPE PLUMBING
J 0
(-1675 4650);
DISPLAY 0.872340 (-1675 4650);
PAINT GREEN (-1675 4650);
DISPLAY INVISIBLE (-1675 4650);
FORCEPROP 1 LAST HDL_TAP TRUE
J 0
(-1350 4475);
DISPLAY 0.872340 (-1350 4475);
DISPLAY INVISIBLE (-1350 4475);
FORCEPROP 1 LAST PATH I131
J 0
(-1677 4600);
DISPLAY 0.872340 (-1677 4600);
PAINT GREEN (-1677 4600);
DISPLAY INVISIBLE (-1677 4600);
FORCEADD TAP..1
(-1875 5050);
FORCEPROP 3 LASTPIN (-1925 5050) SIG_NAME P5E_CPU0_P3_TX_BUF_DP<5>
J 0
(-1915 5060);
DISPLAY 0.659574 (-1915 5060);
PAINT MONO (-1915 5060);
DISPLAY INVISIBLE (-1915 5060);
FORCEPROP 1 LASTPIN (-1925 5050) BN 5
J 0
(-1937 5058);
DISPLAY 0.680851 (-1937 5058);
PAINT GREEN (-1937 5058);
FORCEPROP 2 LAST CDS_LIB standard
J 0
(-1875 5050);
DISPLAY INVISIBLE (-1875 5050);
FORCEPROP 1 LAST BODY_TYPE PLUMBING
J 0
(-1875 5100);
DISPLAY 0.872340 (-1875 5100);
PAINT GREEN (-1875 5100);
DISPLAY INVISIBLE (-1875 5100);
FORCEPROP 1 LAST HDL_TAP TRUE
J 0
(-1550 4925);
DISPLAY 0.872340 (-1550 4925);
DISPLAY INVISIBLE (-1550 4925);
FORCEPROP 1 LAST PATH I132
J 0
(-1877 5050);
DISPLAY 0.872340 (-1877 5050);
PAINT GREEN (-1877 5050);
DISPLAY INVISIBLE (-1877 5050);
FORCEADD TAP..1
(-1675 4950);
FORCEPROP 3 LASTPIN (-1725 4950) SIG_NAME P5E_CPU0_P3_TX_BUF_DN<5>
J 0
(-1715 4960);
DISPLAY 0.659574 (-1715 4960);
PAINT MONO (-1715 4960);
DISPLAY INVISIBLE (-1715 4960);
FORCEPROP 1 LASTPIN (-1725 4950) BN 5
J 0
(-1737 4958);
DISPLAY 0.680851 (-1737 4958);
PAINT GREEN (-1737 4958);
FORCEPROP 2 LAST CDS_LIB standard
J 0
(-1675 4950);
DISPLAY INVISIBLE (-1675 4950);
FORCEPROP 1 LAST BODY_TYPE PLUMBING
J 0
(-1675 5000);
DISPLAY 0.872340 (-1675 5000);
PAINT GREEN (-1675 5000);
DISPLAY INVISIBLE (-1675 5000);
FORCEPROP 1 LAST HDL_TAP TRUE
J 0
(-1350 4825);
DISPLAY 0.872340 (-1350 4825);
DISPLAY INVISIBLE (-1350 4825);
FORCEPROP 1 LAST PATH I133
J 0
(-1677 4950);
DISPLAY 0.872340 (-1677 4950);
PAINT GREEN (-1677 4950);
DISPLAY INVISIBLE (-1677 4950);
FORCEADD TAP..1
(-1875 5400);
FORCEPROP 3 LASTPIN (-1925 5400) SIG_NAME P5E_CPU0_P3_TX_BUF_DP<6>
J 0
(-1915 5410);
DISPLAY 0.659574 (-1915 5410);
PAINT MONO (-1915 5410);
DISPLAY INVISIBLE (-1915 5410);
FORCEPROP 1 LASTPIN (-1925 5400) BN 6
J 0
(-1937 5408);
DISPLAY 0.680851 (-1937 5408);
PAINT GREEN (-1937 5408);
FORCEPROP 2 LAST CDS_LIB standard
J 0
(-1875 5400);
DISPLAY INVISIBLE (-1875 5400);
FORCEPROP 1 LAST BODY_TYPE PLUMBING
J 0
(-1875 5450);
DISPLAY 0.872340 (-1875 5450);
PAINT GREEN (-1875 5450);
DISPLAY INVISIBLE (-1875 5450);
FORCEPROP 1 LAST HDL_TAP TRUE
J 0
(-1550 5275);
DISPLAY 0.872340 (-1550 5275);
DISPLAY INVISIBLE (-1550 5275);
FORCEPROP 1 LAST PATH I134
J 0
(-1877 5400);
DISPLAY 0.872340 (-1877 5400);
PAINT GREEN (-1877 5400);
DISPLAY INVISIBLE (-1877 5400);
FORCEADD TAP..1
(-1875 5750);
FORCEPROP 3 LASTPIN (-1925 5750) SIG_NAME P5E_CPU0_P3_TX_BUF_DP<7>
J 0
(-1915 5760);
DISPLAY 0.659574 (-1915 5760);
PAINT MONO (-1915 5760);
DISPLAY INVISIBLE (-1915 5760);
FORCEPROP 1 LASTPIN (-1925 5750) BN 7
J 0
(-1937 5758);
DISPLAY 0.680851 (-1937 5758);
PAINT GREEN (-1937 5758);
FORCEPROP 2 LAST CDS_LIB standard
J 0
(-1875 5750);
DISPLAY INVISIBLE (-1875 5750);
FORCEPROP 1 LAST BODY_TYPE PLUMBING
J 0
(-1875 5800);
DISPLAY 0.872340 (-1875 5800);
PAINT GREEN (-1875 5800);
DISPLAY INVISIBLE (-1875 5800);
FORCEPROP 1 LAST HDL_TAP TRUE
J 0
(-1550 5625);
DISPLAY 0.872340 (-1550 5625);
DISPLAY INVISIBLE (-1550 5625);
FORCEPROP 1 LAST PATH I135
J 0
(-1877 5750);
DISPLAY 0.872340 (-1877 5750);
PAINT GREEN (-1877 5750);
DISPLAY INVISIBLE (-1877 5750);
FORCEADD TAP..1
(-1675 5300);
FORCEPROP 3 LASTPIN (-1725 5300) SIG_NAME P5E_CPU0_P3_TX_BUF_DN<6>
J 0
(-1715 5310);
DISPLAY 0.659574 (-1715 5310);
PAINT MONO (-1715 5310);
DISPLAY INVISIBLE (-1715 5310);
FORCEPROP 1 LASTPIN (-1725 5300) BN 6
J 0
(-1737 5308);
DISPLAY 0.680851 (-1737 5308);
PAINT GREEN (-1737 5308);
FORCEPROP 2 LAST CDS_LIB standard
J 0
(-1675 5300);
DISPLAY INVISIBLE (-1675 5300);
FORCEPROP 1 LAST BODY_TYPE PLUMBING
J 0
(-1675 5350);
DISPLAY 0.872340 (-1675 5350);
PAINT GREEN (-1675 5350);
DISPLAY INVISIBLE (-1675 5350);
FORCEPROP 1 LAST HDL_TAP TRUE
J 0
(-1350 5175);
DISPLAY 0.872340 (-1350 5175);
DISPLAY INVISIBLE (-1350 5175);
FORCEPROP 1 LAST PATH I136
J 0
(-1677 5300);
DISPLAY 0.872340 (-1677 5300);
PAINT GREEN (-1677 5300);
DISPLAY INVISIBLE (-1677 5300);
FORCEADD TAP..1
(-1675 5650);
FORCEPROP 3 LASTPIN (-1725 5650) SIG_NAME P5E_CPU0_P3_TX_BUF_DN<7>
J 0
(-1715 5660);
DISPLAY 0.659574 (-1715 5660);
PAINT MONO (-1715 5660);
DISPLAY INVISIBLE (-1715 5660);
FORCEPROP 1 LASTPIN (-1725 5650) BN 7
J 0
(-1737 5658);
DISPLAY 0.680851 (-1737 5658);
PAINT GREEN (-1737 5658);
FORCEPROP 2 LAST CDS_LIB standard
J 0
(-1675 5650);
DISPLAY INVISIBLE (-1675 5650);
FORCEPROP 1 LAST BODY_TYPE PLUMBING
J 0
(-1675 5700);
DISPLAY 0.872340 (-1675 5700);
PAINT GREEN (-1675 5700);
DISPLAY INVISIBLE (-1675 5700);
FORCEPROP 1 LAST HDL_TAP TRUE
J 0
(-1350 5525);
DISPLAY 0.872340 (-1350 5525);
DISPLAY INVISIBLE (-1350 5525);
FORCEPROP 1 LAST PATH I137
J 0
(-1677 5650);
DISPLAY 0.872340 (-1677 5650);
PAINT GREEN (-1677 5650);
DISPLAY INVISIBLE (-1677 5650);
FORCEADD OFFPAGE..5
R 2
(-675 5775);
FORCEPROP 2 LAST $XR0 309 
J 0
(-486 5775);
DISPLAY 0.638298 (-486 5775);
PAINT MONO (-486 5775);
FORCEPROP 2 LAST CDS_LIB standard
J 0
(-675 5775);
DISPLAY INVISIBLE (-675 5775);
FORCEPROP 1 LAST OFFPAGE TRUE
J 2
(-1000 5650);
DISPLAY 0.872340 (-1000 5650);
PAINT GREEN (-1000 5650);
DISPLAY INVISIBLE (-1000 5650);
FORCEPROP 1 LAST COMMENT_BODY TRUE
J 2
(-775 5700);
DISPLAY 0.872340 (-775 5700);
PAINT GREEN (-775 5700);
DISPLAY INVISIBLE (-775 5700);
FORCEPROP 2 LAST PATH I138
J 0
(-500 5850);
DISPLAY 0.680851 (-500 5850);
DISPLAY INVISIBLE (-500 5850);
FORCEADD OFFPAGE..5
R 2
(-700 5675);
FORCEPROP 2 LAST $XR0 309 
J 0
(-511 5675);
DISPLAY 0.638298 (-511 5675);
PAINT MONO (-511 5675);
FORCEPROP 2 LAST CDS_LIB standard
J 0
(-700 5675);
DISPLAY INVISIBLE (-700 5675);
FORCEPROP 1 LAST OFFPAGE TRUE
J 2
(-1025 5550);
DISPLAY 0.872340 (-1025 5550);
PAINT GREEN (-1025 5550);
DISPLAY INVISIBLE (-1025 5550);
FORCEPROP 1 LAST COMMENT_BODY TRUE
J 2
(-800 5600);
DISPLAY 0.872340 (-800 5600);
PAINT GREEN (-800 5600);
DISPLAY INVISIBLE (-800 5600);
FORCEPROP 2 LAST PATH I139
J 0
(-525 5750);
DISPLAY 0.680851 (-525 5750);
DISPLAY INVISIBLE (-525 5750);
FORCEADD TAP..1
R 2
(-3450 2000);
FORCEPROP 3 LASTPIN (-3400 2000) SIG_NAME P5E_CPU0_P3_TX_BUF_DN<0>
J 0
(-3390 2010);
DISPLAY 0.659574 (-3390 2010);
PAINT MONO (-3390 2010);
DISPLAY INVISIBLE (-3390 2010);
FORCEPROP 1 LASTPIN (-3400 2000) BN 0
J 2
(-3388 2008);
DISPLAY 0.680851 (-3388 2008);
PAINT GREEN (-3388 2008);
FORCEPROP 2 LAST CDS_LIB standard
J 0
(-3450 2000);
DISPLAY INVISIBLE (-3450 2000);
FORCEPROP 1 LAST BODY_TYPE PLUMBING
J 2
(-3450 2050);
DISPLAY 0.872340 (-3450 2050);
PAINT GREEN (-3450 2050);
DISPLAY INVISIBLE (-3450 2050);
FORCEPROP 1 LAST HDL_TAP TRUE
J 2
(-3775 1875);
DISPLAY 0.872340 (-3775 1875);
DISPLAY INVISIBLE (-3775 1875);
FORCEPROP 1 LAST PATH I14
J 2
(-3448 2000);
DISPLAY 0.872340 (-3448 2000);
PAINT GREEN (-3448 2000);
DISPLAY INVISIBLE (-3448 2000);
FORCEADD TAP..1
(-1675 3900);
FORCEPROP 3 LASTPIN (-1725 3900) SIG_NAME P5E_CPU0_P3_TX_BUF_DN<2>
J 0
(-1715 3910);
DISPLAY 0.659574 (-1715 3910);
PAINT MONO (-1715 3910);
DISPLAY INVISIBLE (-1715 3910);
FORCEPROP 1 LASTPIN (-1725 3900) BN 2
J 0
(-1737 3908);
DISPLAY 0.680851 (-1737 3908);
PAINT GREEN (-1737 3908);
FORCEPROP 2 LAST CDS_LIB standard
J 0
(-1675 3900);
DISPLAY INVISIBLE (-1675 3900);
FORCEPROP 1 LAST BODY_TYPE PLUMBING
J 0
(-1675 3950);
DISPLAY 0.872340 (-1675 3950);
PAINT GREEN (-1675 3950);
DISPLAY INVISIBLE (-1675 3950);
FORCEPROP 1 LAST HDL_TAP TRUE
J 0
(-1350 3775);
DISPLAY 0.872340 (-1350 3775);
DISPLAY INVISIBLE (-1350 3775);
FORCEPROP 1 LAST PATH I140
J 0
(-1677 3900);
DISPLAY 0.872340 (-1677 3900);
PAINT GREEN (-1677 3900);
DISPLAY INVISIBLE (-1677 3900);
FORCEADD TAP..1
(-1875 4000);
FORCEPROP 3 LASTPIN (-1925 4000) SIG_NAME P5E_CPU0_P3_TX_BUF_DP<2>
J 0
(-1915 4010);
DISPLAY 0.659574 (-1915 4010);
PAINT MONO (-1915 4010);
DISPLAY INVISIBLE (-1915 4010);
FORCEPROP 1 LASTPIN (-1925 4000) BN 2
J 0
(-1937 4008);
DISPLAY 0.680851 (-1937 4008);
PAINT GREEN (-1937 4008);
FORCEPROP 2 LAST CDS_LIB standard
J 0
(-1875 4000);
DISPLAY INVISIBLE (-1875 4000);
FORCEPROP 1 LAST BODY_TYPE PLUMBING
J 0
(-1875 4050);
DISPLAY 0.872340 (-1875 4050);
PAINT GREEN (-1875 4050);
DISPLAY INVISIBLE (-1875 4050);
FORCEPROP 1 LAST HDL_TAP TRUE
J 0
(-1550 3875);
DISPLAY 0.872340 (-1550 3875);
DISPLAY INVISIBLE (-1550 3875);
FORCEPROP 1 LAST PATH I141
J 0
(-1877 4000);
DISPLAY 0.872340 (-1877 4000);
PAINT GREEN (-1877 4000);
DISPLAY INVISIBLE (-1877 4000);
FORCEADD PT5161LRS..11
(-2600 4500);
FORCEPROP 1 LAST LOCATION U6013
J 0
(-2950 6125);
DISPLAY 0.723404 (-2950 6125);
PAINT GREEN (-2950 6125);
FORCEPROP 0 LAST $SEC 11
J 0
(-2950 6275);
DISPLAY 0.680851 (-2950 6275);
PAINT MONO (-2950 6275);
DISPLAY INVISIBLE (-2950 6275);
FORCEPROP 0 LAST CDS_SEC 11
J 0
(-2950 6275);
DISPLAY 0.680851 (-2950 6275);
DISPLAY INVISIBLE (-2950 6275);
FORCEPROP 0 LASTPIN (-2150 5650) $PN CK10
J 0
(-2140 5660);
DISPLAY 0.680851 (-2140 5660);
PAINT MONO (-2140 5660);
FORCEPROP 0 LASTPIN (-2150 5300) $PN CU10
J 0
(-2140 5310);
DISPLAY 0.680851 (-2140 5310);
PAINT MONO (-2140 5310);
FORCEPROP 0 LASTPIN (-2150 4950) $PN DD10
J 0
(-2140 4960);
DISPLAY 0.680851 (-2140 4960);
PAINT MONO (-2140 4960);
FORCEPROP 0 LASTPIN (-2150 4600) $PN DL10
J 0
(-2140 4610);
DISPLAY 0.680851 (-2140 4610);
PAINT MONO (-2140 4610);
FORCEPROP 0 LASTPIN (-2150 4250) $PN DV10
J 0
(-2140 4260);
DISPLAY 0.680851 (-2140 4260);
PAINT MONO (-2140 4260);
FORCEPROP 0 LASTPIN (-2150 3900) $PN EE10
J 0
(-2140 3910);
DISPLAY 0.680851 (-2140 3910);
PAINT MONO (-2140 3910);
FORCEPROP 0 LASTPIN (-2150 3550) $PN EM10
J 0
(-2140 3560);
DISPLAY 0.680851 (-2140 3560);
PAINT MONO (-2140 3560);
FORCEPROP 0 LASTPIN (-2150 3200) $PN EW10
J 0
(-2140 3210);
DISPLAY 0.680851 (-2140 3210);
PAINT MONO (-2140 3210);
FORCEPROP 0 LASTPIN (-2150 5750) $PN CH7
J 0
(-2140 5760);
DISPLAY 0.680851 (-2140 5760);
PAINT MONO (-2140 5760);
FORCEPROP 0 LASTPIN (-2150 5400) $PN CR7
J 0
(-2140 5410);
DISPLAY 0.680851 (-2140 5410);
PAINT MONO (-2140 5410);
FORCEPROP 0 LASTPIN (-2150 5050) $PN DB7
J 0
(-2140 5060);
DISPLAY 0.680851 (-2140 5060);
PAINT MONO (-2140 5060);
FORCEPROP 0 LASTPIN (-2150 4700) $PN DJ7
J 0
(-2140 4710);
DISPLAY 0.680851 (-2140 4710);
PAINT MONO (-2140 4710);
FORCEPROP 0 LASTPIN (-2150 4350) $PN DT7
J 0
(-2140 4360);
DISPLAY 0.680851 (-2140 4360);
PAINT MONO (-2140 4360);
FORCEPROP 0 LASTPIN (-2150 4000) $PN EC7
J 0
(-2140 4010);
DISPLAY 0.680851 (-2140 4010);
PAINT MONO (-2140 4010);
FORCEPROP 0 LASTPIN (-2150 3650) $PN EK7
J 0
(-2140 3660);
DISPLAY 0.680851 (-2140 3660);
PAINT MONO (-2140 3660);
FORCEPROP 0 LASTPIN (-2150 3300) $PN EU7
J 0
(-2140 3310);
DISPLAY 0.680851 (-2140 3310);
PAINT MONO (-2140 3310);
FORCEPROP 2 LAST VALUE PT5161LRS
J 0
(-2950 6175);
DISPLAY 0.680851 (-2950 6175);
FORCEPROP 1 LAST MATERIAL IC
J 0
(-2950 5975);
DISPLAY 0.723404 (-2950 5975);
PAINT GREEN (-2950 5975);
FORCEPROP 2 LAST PART_TYPE SMLF
J 0
(-2950 6225);
DISPLAY 0.680851 (-2950 6225);
FORCEPROP 1 LAST NEEDS_NO_SIZE TRUE
J 0
(-2600 4500);
DISPLAY 0.723404 (-2600 4500);
PAINT GREEN (-2600 4500);
DISPLAY INVISIBLE (-2600 4500);
FORCEPROP 1 LAST CDS_LMAN_SYM_OUTLINE -350,1450,300,-1400
J 0
(-2600 4500);
DISPLAY 0.468085 (-2600 4500);
PAINT GREEN (-2600 4500);
DISPLAY INVISIBLE (-2600 4500);
FORCEPROP 2 LAST CDS_LIB pure_quanta
J 0
(-2600 4500);
DISPLAY INVISIBLE (-2600 4500);
FORCEPROP 1 LAST PATH I142
J 0
(-2600 4500);
DISPLAY 0.723404 (-2600 4500);
PAINT GREEN (-2600 4500);
DISPLAY INVISIBLE (-2600 4500);
FORCEPROP 1 LAST PART_NUMBER AJ051610U03
J 0
(-2950 6050);
DISPLAY 0.723404 (-2950 6050);
PAINT GREEN (-2950 6050);
DISPLAY INVISIBLE (-2950 6050);
FORCEADD TAP..1
R 2
(-3450 1600);
FORCEPROP 3 LASTPIN (-3400 1600) SIG_NAME P5E_CPU0_P3_TX_BUF_DN<2>
J 0
(-3390 1610);
DISPLAY 0.659574 (-3390 1610);
PAINT MONO (-3390 1610);
DISPLAY INVISIBLE (-3390 1610);
FORCEPROP 1 LASTPIN (-3400 1600) BN 2
J 2
(-3388 1608);
DISPLAY 0.680851 (-3388 1608);
PAINT GREEN (-3388 1608);
FORCEPROP 2 LAST CDS_LIB standard
J 0
(-3450 1600);
DISPLAY INVISIBLE (-3450 1600);
FORCEPROP 1 LAST BODY_TYPE PLUMBING
J 2
(-3450 1650);
DISPLAY 0.872340 (-3450 1650);
PAINT GREEN (-3450 1650);
DISPLAY INVISIBLE (-3450 1650);
FORCEPROP 1 LAST HDL_TAP TRUE
J 2
(-3775 1475);
DISPLAY 0.872340 (-3775 1475);
DISPLAY INVISIBLE (-3775 1475);
FORCEPROP 1 LAST PATH I15
J 2
(-3448 1600);
DISPLAY 0.872340 (-3448 1600);
PAINT GREEN (-3448 1600);
DISPLAY INVISIBLE (-3448 1600);
FORCEADD TAP..1
R 2
(-3200 1650);
FORCEPROP 3 LASTPIN (-3150 1650) SIG_NAME P5E_CPU0_P3_TX_BUF_DP<2>
J 0
(-3140 1660);
DISPLAY 0.659574 (-3140 1660);
PAINT MONO (-3140 1660);
DISPLAY INVISIBLE (-3140 1660);
FORCEPROP 1 LASTPIN (-3150 1650) BN 2
J 2
(-3138 1658);
DISPLAY 0.680851 (-3138 1658);
PAINT GREEN (-3138 1658);
FORCEPROP 2 LAST CDS_LIB standard
J 0
(-3200 1650);
DISPLAY INVISIBLE (-3200 1650);
FORCEPROP 1 LAST BODY_TYPE PLUMBING
J 2
(-3200 1700);
DISPLAY 0.872340 (-3200 1700);
PAINT GREEN (-3200 1700);
DISPLAY INVISIBLE (-3200 1700);
FORCEPROP 1 LAST HDL_TAP TRUE
J 2
(-3525 1525);
DISPLAY 0.872340 (-3525 1525);
DISPLAY INVISIBLE (-3525 1525);
FORCEPROP 1 LAST PATH I16
J 2
(-3198 1650);
DISPLAY 0.872340 (-3198 1650);
PAINT GREEN (-3198 1650);
DISPLAY INVISIBLE (-3198 1650);
FORCEADD TAP..1
R 2
(-3200 1850);
FORCEPROP 3 LASTPIN (-3150 1850) SIG_NAME P5E_CPU0_P3_TX_BUF_DP<1>
J 0
(-3140 1860);
DISPLAY 0.659574 (-3140 1860);
PAINT MONO (-3140 1860);
DISPLAY INVISIBLE (-3140 1860);
FORCEPROP 1 LASTPIN (-3150 1850) BN 1
J 2
(-3138 1858);
DISPLAY 0.680851 (-3138 1858);
PAINT GREEN (-3138 1858);
FORCEPROP 2 LAST CDS_LIB standard
J 0
(-3200 1850);
DISPLAY INVISIBLE (-3200 1850);
FORCEPROP 1 LAST BODY_TYPE PLUMBING
J 2
(-3200 1900);
DISPLAY 0.872340 (-3200 1900);
PAINT GREEN (-3200 1900);
DISPLAY INVISIBLE (-3200 1900);
FORCEPROP 1 LAST HDL_TAP TRUE
J 2
(-3525 1725);
DISPLAY 0.872340 (-3525 1725);
DISPLAY INVISIBLE (-3525 1725);
FORCEPROP 1 LAST PATH I17
J 2
(-3198 1850);
DISPLAY 0.872340 (-3198 1850);
PAINT GREEN (-3198 1850);
DISPLAY INVISIBLE (-3198 1850);
FORCEADD TAP..1
R 2
(-3200 2050);
FORCEPROP 3 LASTPIN (-3150 2050) SIG_NAME P5E_CPU0_P3_TX_BUF_DP<0>
J 0
(-3140 2060);
DISPLAY 0.659574 (-3140 2060);
PAINT MONO (-3140 2060);
DISPLAY INVISIBLE (-3140 2060);
FORCEPROP 1 LASTPIN (-3150 2050) BN 0
J 2
(-3138 2058);
DISPLAY 0.680851 (-3138 2058);
PAINT GREEN (-3138 2058);
FORCEPROP 2 LAST CDS_LIB standard
J 0
(-3200 2050);
DISPLAY INVISIBLE (-3200 2050);
FORCEPROP 1 LAST BODY_TYPE PLUMBING
J 2
(-3200 2100);
DISPLAY 0.872340 (-3200 2100);
PAINT GREEN (-3200 2100);
DISPLAY INVISIBLE (-3200 2100);
FORCEPROP 1 LAST HDL_TAP TRUE
J 2
(-3525 1925);
DISPLAY 0.872340 (-3525 1925);
DISPLAY INVISIBLE (-3525 1925);
FORCEPROP 1 LAST PATH I18
J 2
(-3198 2050);
DISPLAY 0.872340 (-3198 2050);
PAINT GREEN (-3198 2050);
DISPLAY INVISIBLE (-3198 2050);
FORCEADD Q_CAP_DIFFBUS..2
R 2
(-2475 650);
FORCEPROP 1 LAST LOCATION C6611
J 2
(-2200 650);
DISPLAY 0.723404 (-2200 650);
PAINT GREEN (-2200 650);
FORCEPROP 2 LAST $SEC 1
J 2
(-2300 725);
DISPLAY 0.680851 (-2300 725);
PAINT MONO (-2300 725);
DISPLAY INVISIBLE (-2300 725);
FORCEPROP 2 LAST CDS_SEC 1
J 2
(-2300 725);
DISPLAY 0.680851 (-2300 725);
DISPLAY INVISIBLE (-2300 725);
FORCEPROP 2 LASTPIN (-2400 650) $PN 1
J 0
(-2390 660);
DISPLAY 0.808511 (-2390 660);
FORCEPROP 2 LASTPIN (-2550 650) $PN 2
J 2
(-2560 660);
DISPLAY 0.808511 (-2560 660);
FORCEPROP 2 LAST VALUE DIFF BUS_0.22UF
J 2
(-2625 650);
DISPLAY 0.553191 (-2625 650);
FORCEPROP 2 LAST TOLERANCE 20%
J 2
(-2550 700);
DISPLAY 0.553191 (-2550 700);
DISPLAY INVISIBLE (-2550 700);
FORCEPROP 2 LAST PACK_TYPE C0201
J 2
(-2650 700);
DISPLAY 0.553191 (-2650 700);
DISPLAY INVISIBLE (-2650 700);
FORCEPROP 1 LAST MATERIAL X6S
J 2
(-2466 729);
DISPLAY 0.574468 (-2466 729);
PAINT GREEN (-2466 729);
DISPLAY INVISIBLE (-2466 729);
FORCEPROP 2 LAST VOLTAGE 6.3V
J 2
(-2825 700);
DISPLAY 0.553191 (-2825 700);
DISPLAY INVISIBLE (-2825 700);
FORCEPROP 1 LAST PIN_NAMES_ROTATE TRUE
J 2
(-2475 650);
DISPLAY 0.489362 (-2475 650);
PAINT GREEN (-2475 650);
DISPLAY INVISIBLE (-2475 650);
FORCEPROP 2 LAST CDS_LIB pure_quanta
J 2
(-2475 650);
DISPLAY INVISIBLE (-2475 650);
FORCEPROP 1 LAST CDS_LMAN_SYM_OUTLINE -25,50,25,-50
J 2
(-2475 650);
DISPLAY 0.468085 (-2475 650);
PAINT GREEN (-2475 650);
DISPLAY INVISIBLE (-2475 650);
FORCEPROP 1 LAST PATH I19
J 2
(-2475 650);
DISPLAY 0.723404 (-2475 650);
DISPLAY INVISIBLE (-2475 650);
FORCEPROP 1 LAST PART_NUMBER SP_CH4221MEE01
J 2
(-2591 738);
DISPLAY 0.574468 (-2591 738);
PAINT GREEN (-2591 738);
DISPLAY INVISIBLE (-2591 738);
FORCEPROP 1 LAST LOCATION C6611
J 0
(-2225 725);
DISPLAY 1.021277 (-2225 725);
DISPLAY INVISIBLE (-2225 725);
FORCEADD OFFPAGE..1
(-4400 2075);
FORCEPROP 2 LAST $XR0 309 
J 0
(-4652 2075);
DISPLAY 0.638298 (-4652 2075);
PAINT MONO (-4652 2075);
FORCEPROP 2 LAST CDS_LIB standard
J 0
(-4400 2075);
DISPLAY INVISIBLE (-4400 2075);
FORCEPROP 1 LAST OFFPAGE TRUE
J 0
(-4075 1950);
DISPLAY 0.872340 (-4075 1950);
DISPLAY INVISIBLE (-4075 1950);
FORCEPROP 1 LAST COMMENT_BODY TRUE
J 0
(-4275 1975);
DISPLAY 0.872340 (-4275 1975);
PAINT GREEN (-4275 1975);
DISPLAY INVISIBLE (-4275 1975);
FORCEPROP 2 LAST PATH I2
J 0
(-4650 2125);
DISPLAY 0.680851 (-4650 2125);
DISPLAY INVISIBLE (-4650 2125);
FORCEADD Q_CAP_DIFFBUS..2
R 2
(-2475 600);
FORCEPROP 1 LAST LOCATION C6612
J 2
(-2200 600);
DISPLAY 0.723404 (-2200 600);
PAINT GREEN (-2200 600);
FORCEPROP 2 LAST $SEC 1
J 2
(-2300 675);
DISPLAY 0.680851 (-2300 675);
PAINT MONO (-2300 675);
DISPLAY INVISIBLE (-2300 675);
FORCEPROP 2 LAST CDS_SEC 1
J 2
(-2300 675);
DISPLAY 0.680851 (-2300 675);
DISPLAY INVISIBLE (-2300 675);
FORCEPROP 2 LASTPIN (-2400 600) $PN 1
J 0
(-2390 610);
DISPLAY 0.808511 (-2390 610);
FORCEPROP 2 LASTPIN (-2550 600) $PN 2
J 2
(-2560 610);
DISPLAY 0.808511 (-2560 610);
FORCEPROP 2 LAST VALUE DIFF BUS_0.22UF
J 2
(-2625 600);
DISPLAY 0.553191 (-2625 600);
FORCEPROP 2 LAST TOLERANCE 20%
J 2
(-2550 650);
DISPLAY 0.553191 (-2550 650);
DISPLAY INVISIBLE (-2550 650);
FORCEPROP 2 LAST PACK_TYPE C0201
J 2
(-2650 650);
DISPLAY 0.553191 (-2650 650);
DISPLAY INVISIBLE (-2650 650);
FORCEPROP 1 LAST MATERIAL X6S
J 2
(-2466 679);
DISPLAY 0.574468 (-2466 679);
PAINT GREEN (-2466 679);
DISPLAY INVISIBLE (-2466 679);
FORCEPROP 2 LAST VOLTAGE 6.3V
J 2
(-2825 650);
DISPLAY 0.553191 (-2825 650);
DISPLAY INVISIBLE (-2825 650);
FORCEPROP 1 LAST PIN_NAMES_ROTATE TRUE
J 2
(-2475 600);
DISPLAY 0.489362 (-2475 600);
PAINT GREEN (-2475 600);
DISPLAY INVISIBLE (-2475 600);
FORCEPROP 2 LAST CDS_LIB pure_quanta
J 2
(-2475 600);
DISPLAY INVISIBLE (-2475 600);
FORCEPROP 1 LAST CDS_LMAN_SYM_OUTLINE -25,50,25,-50
J 2
(-2475 600);
DISPLAY 0.468085 (-2475 600);
PAINT GREEN (-2475 600);
DISPLAY INVISIBLE (-2475 600);
FORCEPROP 1 LAST PATH I20
J 2
(-2475 600);
DISPLAY 0.723404 (-2475 600);
DISPLAY INVISIBLE (-2475 600);
FORCEPROP 1 LAST PART_NUMBER SP_CH4221MEE01
J 2
(-2591 688);
DISPLAY 0.574468 (-2591 688);
PAINT GREEN (-2591 688);
DISPLAY INVISIBLE (-2591 688);
FORCEPROP 1 LAST LOCATION C6612
J 0
(-2225 675);
DISPLAY 1.021277 (-2225 675);
DISPLAY INVISIBLE (-2225 675);
FORCEADD Q_CAP_DIFFBUS..2
R 2
(-2475 800);
FORCEPROP 1 LAST LOCATION C6610
J 2
(-2200 800);
DISPLAY 0.723404 (-2200 800);
PAINT GREEN (-2200 800);
FORCEPROP 2 LAST $SEC 1
J 2
(-2300 875);
DISPLAY 0.680851 (-2300 875);
PAINT MONO (-2300 875);
DISPLAY INVISIBLE (-2300 875);
FORCEPROP 2 LAST CDS_SEC 1
J 2
(-2300 875);
DISPLAY 0.680851 (-2300 875);
DISPLAY INVISIBLE (-2300 875);
FORCEPROP 2 LASTPIN (-2400 800) $PN 1
J 0
(-2390 810);
DISPLAY 0.808511 (-2390 810);
FORCEPROP 2 LASTPIN (-2550 800) $PN 2
J 2
(-2560 810);
DISPLAY 0.808511 (-2560 810);
FORCEPROP 2 LAST VALUE DIFF BUS_0.22UF
J 2
(-2625 800);
DISPLAY 0.553191 (-2625 800);
FORCEPROP 2 LAST TOLERANCE 20%
J 2
(-2550 850);
DISPLAY 0.553191 (-2550 850);
DISPLAY INVISIBLE (-2550 850);
FORCEPROP 2 LAST PACK_TYPE C0201
J 2
(-2650 850);
DISPLAY 0.553191 (-2650 850);
DISPLAY INVISIBLE (-2650 850);
FORCEPROP 1 LAST MATERIAL X6S
J 2
(-2466 879);
DISPLAY 0.574468 (-2466 879);
PAINT GREEN (-2466 879);
DISPLAY INVISIBLE (-2466 879);
FORCEPROP 2 LAST VOLTAGE 6.3V
J 2
(-2825 850);
DISPLAY 0.553191 (-2825 850);
DISPLAY INVISIBLE (-2825 850);
FORCEPROP 1 LAST PIN_NAMES_ROTATE TRUE
J 2
(-2475 800);
DISPLAY 0.489362 (-2475 800);
PAINT GREEN (-2475 800);
DISPLAY INVISIBLE (-2475 800);
FORCEPROP 2 LAST CDS_LIB pure_quanta
J 2
(-2475 800);
DISPLAY INVISIBLE (-2475 800);
FORCEPROP 1 LAST CDS_LMAN_SYM_OUTLINE -25,50,25,-50
J 2
(-2475 800);
DISPLAY 0.468085 (-2475 800);
PAINT GREEN (-2475 800);
DISPLAY INVISIBLE (-2475 800);
FORCEPROP 1 LAST PATH I21
J 2
(-2475 800);
DISPLAY 0.723404 (-2475 800);
DISPLAY INVISIBLE (-2475 800);
FORCEPROP 1 LAST PART_NUMBER SP_CH4221MEE01
J 2
(-2591 888);
DISPLAY 0.574468 (-2591 888);
PAINT GREEN (-2591 888);
DISPLAY INVISIBLE (-2591 888);
FORCEPROP 1 LAST LOCATION C6610
J 0
(-2225 875);
DISPLAY 1.021277 (-2225 875);
DISPLAY INVISIBLE (-2225 875);
FORCEADD Q_CAP_DIFFBUS..2
R 2
(-2475 850);
FORCEPROP 1 LAST LOCATION C6609
J 2
(-2200 850);
DISPLAY 0.723404 (-2200 850);
PAINT GREEN (-2200 850);
FORCEPROP 2 LAST $SEC 1
J 2
(-2300 925);
DISPLAY 0.680851 (-2300 925);
PAINT MONO (-2300 925);
DISPLAY INVISIBLE (-2300 925);
FORCEPROP 2 LAST CDS_SEC 1
J 2
(-2300 925);
DISPLAY 0.680851 (-2300 925);
DISPLAY INVISIBLE (-2300 925);
FORCEPROP 2 LASTPIN (-2400 850) $PN 1
J 0
(-2390 860);
DISPLAY 0.808511 (-2390 860);
FORCEPROP 2 LASTPIN (-2550 850) $PN 2
J 2
(-2560 860);
DISPLAY 0.808511 (-2560 860);
FORCEPROP 2 LAST VALUE DIFF BUS_0.22UF
J 2
(-2625 850);
DISPLAY 0.553191 (-2625 850);
FORCEPROP 2 LAST TOLERANCE 20%
J 2
(-2550 900);
DISPLAY 0.553191 (-2550 900);
DISPLAY INVISIBLE (-2550 900);
FORCEPROP 2 LAST PACK_TYPE C0201
J 2
(-2650 900);
DISPLAY 0.553191 (-2650 900);
DISPLAY INVISIBLE (-2650 900);
FORCEPROP 1 LAST MATERIAL X6S
J 2
(-2466 929);
DISPLAY 0.574468 (-2466 929);
PAINT GREEN (-2466 929);
DISPLAY INVISIBLE (-2466 929);
FORCEPROP 2 LAST VOLTAGE 6.3V
J 2
(-2825 900);
DISPLAY 0.553191 (-2825 900);
DISPLAY INVISIBLE (-2825 900);
FORCEPROP 1 LAST PIN_NAMES_ROTATE TRUE
J 2
(-2475 850);
DISPLAY 0.489362 (-2475 850);
PAINT GREEN (-2475 850);
DISPLAY INVISIBLE (-2475 850);
FORCEPROP 1 LAST CDS_LMAN_SYM_OUTLINE -25,50,25,-50
J 2
(-2475 850);
DISPLAY 0.468085 (-2475 850);
PAINT GREEN (-2475 850);
DISPLAY INVISIBLE (-2475 850);
FORCEPROP 2 LAST CDS_LIB pure_quanta
J 2
(-2475 850);
DISPLAY INVISIBLE (-2475 850);
FORCEPROP 1 LAST PATH I22
J 2
(-2475 850);
DISPLAY 0.723404 (-2475 850);
DISPLAY INVISIBLE (-2475 850);
FORCEPROP 1 LAST PART_NUMBER SP_CH4221MEE01
J 2
(-2591 938);
DISPLAY 0.574468 (-2591 938);
PAINT GREEN (-2591 938);
DISPLAY INVISIBLE (-2591 938);
FORCEPROP 1 LAST LOCATION C6609
J 0
(-2225 925);
DISPLAY 1.021277 (-2225 925);
DISPLAY INVISIBLE (-2225 925);
FORCEADD Q_CAP_DIFFBUS..2
R 2
(-2475 1000);
FORCEPROP 1 LAST LOCATION C6608
J 2
(-2200 1000);
DISPLAY 0.723404 (-2200 1000);
PAINT GREEN (-2200 1000);
FORCEPROP 2 LAST $SEC 1
J 2
(-2300 1075);
DISPLAY 0.680851 (-2300 1075);
PAINT MONO (-2300 1075);
DISPLAY INVISIBLE (-2300 1075);
FORCEPROP 2 LAST CDS_SEC 1
J 2
(-2300 1075);
DISPLAY 0.680851 (-2300 1075);
DISPLAY INVISIBLE (-2300 1075);
FORCEPROP 2 LASTPIN (-2400 1000) $PN 1
J 0
(-2390 1010);
DISPLAY 0.808511 (-2390 1010);
FORCEPROP 2 LASTPIN (-2550 1000) $PN 2
J 2
(-2560 1010);
DISPLAY 0.808511 (-2560 1010);
FORCEPROP 2 LAST VALUE DIFF BUS_0.22UF
J 2
(-2625 1000);
DISPLAY 0.553191 (-2625 1000);
FORCEPROP 2 LAST TOLERANCE 20%
J 2
(-2550 1050);
DISPLAY 0.553191 (-2550 1050);
DISPLAY INVISIBLE (-2550 1050);
FORCEPROP 2 LAST PACK_TYPE C0201
J 2
(-2650 1050);
DISPLAY 0.553191 (-2650 1050);
DISPLAY INVISIBLE (-2650 1050);
FORCEPROP 1 LAST MATERIAL X6S
J 2
(-2466 1079);
DISPLAY 0.574468 (-2466 1079);
PAINT GREEN (-2466 1079);
DISPLAY INVISIBLE (-2466 1079);
FORCEPROP 2 LAST VOLTAGE 6.3V
J 2
(-2825 1050);
DISPLAY 0.553191 (-2825 1050);
DISPLAY INVISIBLE (-2825 1050);
FORCEPROP 1 LAST PIN_NAMES_ROTATE TRUE
J 2
(-2475 1000);
DISPLAY 0.489362 (-2475 1000);
PAINT GREEN (-2475 1000);
DISPLAY INVISIBLE (-2475 1000);
FORCEPROP 2 LAST CDS_LIB pure_quanta
J 2
(-2475 1000);
DISPLAY INVISIBLE (-2475 1000);
FORCEPROP 1 LAST CDS_LMAN_SYM_OUTLINE -25,50,25,-50
J 2
(-2475 1000);
DISPLAY 0.468085 (-2475 1000);
PAINT GREEN (-2475 1000);
DISPLAY INVISIBLE (-2475 1000);
FORCEPROP 1 LAST PATH I23
J 2
(-2475 1000);
DISPLAY 0.723404 (-2475 1000);
DISPLAY INVISIBLE (-2475 1000);
FORCEPROP 1 LAST PART_NUMBER SP_CH4221MEE01
J 2
(-2591 1088);
DISPLAY 0.574468 (-2591 1088);
PAINT GREEN (-2591 1088);
DISPLAY INVISIBLE (-2591 1088);
FORCEPROP 1 LAST LOCATION C6608
J 0
(-2225 1075);
DISPLAY 1.021277 (-2225 1075);
DISPLAY INVISIBLE (-2225 1075);
FORCEADD Q_CAP_DIFFBUS..2
R 2
(-2475 1050);
FORCEPROP 1 LAST LOCATION C6607
J 2
(-2200 1050);
DISPLAY 0.723404 (-2200 1050);
PAINT GREEN (-2200 1050);
FORCEPROP 2 LAST $SEC 1
J 2
(-2300 1125);
DISPLAY 0.680851 (-2300 1125);
PAINT MONO (-2300 1125);
DISPLAY INVISIBLE (-2300 1125);
FORCEPROP 2 LAST CDS_SEC 1
J 2
(-2300 1125);
DISPLAY 0.680851 (-2300 1125);
DISPLAY INVISIBLE (-2300 1125);
FORCEPROP 2 LASTPIN (-2400 1050) $PN 1
J 0
(-2390 1060);
DISPLAY 0.808511 (-2390 1060);
FORCEPROP 2 LASTPIN (-2550 1050) $PN 2
J 2
(-2560 1060);
DISPLAY 0.808511 (-2560 1060);
FORCEPROP 2 LAST VALUE DIFF BUS_0.22UF
J 2
(-2625 1050);
DISPLAY 0.553191 (-2625 1050);
FORCEPROP 2 LAST TOLERANCE 20%
J 2
(-2550 1100);
DISPLAY 0.553191 (-2550 1100);
DISPLAY INVISIBLE (-2550 1100);
FORCEPROP 2 LAST PACK_TYPE C0201
J 2
(-2650 1100);
DISPLAY 0.553191 (-2650 1100);
DISPLAY INVISIBLE (-2650 1100);
FORCEPROP 1 LAST MATERIAL X6S
J 2
(-2466 1129);
DISPLAY 0.574468 (-2466 1129);
PAINT GREEN (-2466 1129);
DISPLAY INVISIBLE (-2466 1129);
FORCEPROP 2 LAST VOLTAGE 6.3V
J 2
(-2825 1100);
DISPLAY 0.553191 (-2825 1100);
DISPLAY INVISIBLE (-2825 1100);
FORCEPROP 1 LAST PIN_NAMES_ROTATE TRUE
J 2
(-2475 1050);
DISPLAY 0.489362 (-2475 1050);
PAINT GREEN (-2475 1050);
DISPLAY INVISIBLE (-2475 1050);
FORCEPROP 2 LAST CDS_LIB pure_quanta
J 2
(-2475 1050);
DISPLAY INVISIBLE (-2475 1050);
FORCEPROP 1 LAST CDS_LMAN_SYM_OUTLINE -25,50,25,-50
J 2
(-2475 1050);
DISPLAY 0.468085 (-2475 1050);
PAINT GREEN (-2475 1050);
DISPLAY INVISIBLE (-2475 1050);
FORCEPROP 1 LAST PATH I24
J 2
(-2475 1050);
DISPLAY 0.723404 (-2475 1050);
DISPLAY INVISIBLE (-2475 1050);
FORCEPROP 1 LAST PART_NUMBER SP_CH4221MEE01
J 2
(-2591 1138);
DISPLAY 0.574468 (-2591 1138);
PAINT GREEN (-2591 1138);
DISPLAY INVISIBLE (-2591 1138);
FORCEPROP 1 LAST LOCATION C6607
J 0
(-2225 1125);
DISPLAY 1.021277 (-2225 1125);
DISPLAY INVISIBLE (-2225 1125);
FORCEADD TAP..1
(-1925 1050);
FORCEPROP 3 LASTPIN (-1975 1050) SIG_NAME P5E_CPU0_P3_TX_BUF_C_DP<5>
J 0
(-1965 1060);
DISPLAY 0.659574 (-1965 1060);
PAINT MONO (-1965 1060);
DISPLAY INVISIBLE (-1965 1060);
FORCEPROP 1 LASTPIN (-1975 1050) BN 5
J 0
(-1987 1058);
DISPLAY 0.680851 (-1987 1058);
PAINT GREEN (-1987 1058);
FORCEPROP 2 LAST CDS_LIB standard
J 0
(-1925 1050);
DISPLAY INVISIBLE (-1925 1050);
FORCEPROP 1 LAST BODY_TYPE PLUMBING
J 0
(-1925 1100);
DISPLAY 0.872340 (-1925 1100);
PAINT GREEN (-1925 1100);
DISPLAY INVISIBLE (-1925 1100);
FORCEPROP 1 LAST HDL_TAP TRUE
J 0
(-1600 925);
DISPLAY 0.872340 (-1600 925);
DISPLAY INVISIBLE (-1600 925);
FORCEPROP 1 LAST PATH I25
J 0
(-1927 1050);
DISPLAY 0.872340 (-1927 1050);
PAINT GREEN (-1927 1050);
DISPLAY INVISIBLE (-1927 1050);
FORCEADD TAP..1
(-1925 850);
FORCEPROP 3 LASTPIN (-1975 850) SIG_NAME P5E_CPU0_P3_TX_BUF_C_DP<6>
J 0
(-1965 860);
DISPLAY 0.659574 (-1965 860);
PAINT MONO (-1965 860);
DISPLAY INVISIBLE (-1965 860);
FORCEPROP 1 LASTPIN (-1975 850) BN 6
J 0
(-1987 858);
DISPLAY 0.680851 (-1987 858);
PAINT GREEN (-1987 858);
FORCEPROP 2 LAST CDS_LIB standard
J 0
(-1925 850);
DISPLAY INVISIBLE (-1925 850);
FORCEPROP 1 LAST BODY_TYPE PLUMBING
J 0
(-1925 900);
DISPLAY 0.872340 (-1925 900);
PAINT GREEN (-1925 900);
DISPLAY INVISIBLE (-1925 900);
FORCEPROP 1 LAST HDL_TAP TRUE
J 0
(-1600 725);
DISPLAY 0.872340 (-1600 725);
DISPLAY INVISIBLE (-1600 725);
FORCEPROP 1 LAST PATH I26
J 0
(-1927 850);
DISPLAY 0.872340 (-1927 850);
PAINT GREEN (-1927 850);
DISPLAY INVISIBLE (-1927 850);
FORCEADD TAP..1
(-1925 650);
FORCEPROP 3 LASTPIN (-1975 650) SIG_NAME P5E_CPU0_P3_TX_BUF_C_DP<7>
J 0
(-1965 660);
DISPLAY 0.659574 (-1965 660);
PAINT MONO (-1965 660);
DISPLAY INVISIBLE (-1965 660);
FORCEPROP 1 LASTPIN (-1975 650) BN 7
J 0
(-1987 658);
DISPLAY 0.680851 (-1987 658);
PAINT GREEN (-1987 658);
FORCEPROP 2 LAST CDS_LIB standard
J 0
(-1925 650);
DISPLAY INVISIBLE (-1925 650);
FORCEPROP 1 LAST BODY_TYPE PLUMBING
J 0
(-1925 700);
DISPLAY 0.872340 (-1925 700);
PAINT GREEN (-1925 700);
DISPLAY INVISIBLE (-1925 700);
FORCEPROP 1 LAST HDL_TAP TRUE
J 0
(-1600 525);
DISPLAY 0.872340 (-1600 525);
DISPLAY INVISIBLE (-1600 525);
FORCEPROP 1 LAST PATH I27
J 0
(-1927 650);
DISPLAY 0.872340 (-1927 650);
PAINT GREEN (-1927 650);
DISPLAY INVISIBLE (-1927 650);
FORCEADD TAP..1
(-1725 800);
FORCEPROP 3 LASTPIN (-1775 800) SIG_NAME P5E_CPU0_P3_TX_BUF_C_DN<6>
J 0
(-1765 810);
DISPLAY 0.659574 (-1765 810);
PAINT MONO (-1765 810);
DISPLAY INVISIBLE (-1765 810);
FORCEPROP 1 LASTPIN (-1775 800) BN 6
J 0
(-1787 808);
DISPLAY 0.680851 (-1787 808);
PAINT GREEN (-1787 808);
FORCEPROP 2 LAST CDS_LIB standard
J 0
(-1725 800);
DISPLAY INVISIBLE (-1725 800);
FORCEPROP 1 LAST BODY_TYPE PLUMBING
J 0
(-1725 850);
DISPLAY 0.872340 (-1725 850);
PAINT GREEN (-1725 850);
DISPLAY INVISIBLE (-1725 850);
FORCEPROP 1 LAST HDL_TAP TRUE
J 0
(-1400 675);
DISPLAY 0.872340 (-1400 675);
DISPLAY INVISIBLE (-1400 675);
FORCEPROP 1 LAST PATH I28
J 0
(-1727 800);
DISPLAY 0.872340 (-1727 800);
PAINT GREEN (-1727 800);
DISPLAY INVISIBLE (-1727 800);
FORCEADD TAP..1
(-1725 600);
FORCEPROP 3 LASTPIN (-1775 600) SIG_NAME P5E_CPU0_P3_TX_BUF_C_DN<7>
J 0
(-1765 610);
DISPLAY 0.659574 (-1765 610);
PAINT MONO (-1765 610);
DISPLAY INVISIBLE (-1765 610);
FORCEPROP 1 LASTPIN (-1775 600) BN 7
J 0
(-1787 608);
DISPLAY 0.680851 (-1787 608);
PAINT GREEN (-1787 608);
FORCEPROP 2 LAST CDS_LIB standard
J 0
(-1725 600);
DISPLAY INVISIBLE (-1725 600);
FORCEPROP 1 LAST BODY_TYPE PLUMBING
J 0
(-1725 650);
DISPLAY 0.872340 (-1725 650);
PAINT GREEN (-1725 650);
DISPLAY INVISIBLE (-1725 650);
FORCEPROP 1 LAST HDL_TAP TRUE
J 0
(-1400 475);
DISPLAY 0.872340 (-1400 475);
DISPLAY INVISIBLE (-1400 475);
FORCEPROP 1 LAST PATH I29
J 0
(-1727 600);
DISPLAY 0.872340 (-1727 600);
PAINT GREEN (-1727 600);
DISPLAY INVISIBLE (-1727 600);
FORCEADD TAP..1
R 2
(-3450 1000);
FORCEPROP 3 LASTPIN (-3400 1000) SIG_NAME P5E_CPU0_P3_TX_BUF_DN<5>
J 0
(-3390 1010);
DISPLAY 0.659574 (-3390 1010);
PAINT MONO (-3390 1010);
DISPLAY INVISIBLE (-3390 1010);
FORCEPROP 1 LASTPIN (-3400 1000) BN 5
J 2
(-3388 1008);
DISPLAY 0.680851 (-3388 1008);
PAINT GREEN (-3388 1008);
FORCEPROP 2 LAST CDS_LIB standard
J 0
(-3450 1000);
DISPLAY INVISIBLE (-3450 1000);
FORCEPROP 1 LAST BODY_TYPE PLUMBING
J 2
(-3450 1050);
DISPLAY 0.872340 (-3450 1050);
PAINT GREEN (-3450 1050);
DISPLAY INVISIBLE (-3450 1050);
FORCEPROP 1 LAST HDL_TAP TRUE
J 2
(-3775 875);
DISPLAY 0.872340 (-3775 875);
DISPLAY INVISIBLE (-3775 875);
FORCEPROP 1 LAST PATH I3
J 2
(-3448 1000);
DISPLAY 0.872340 (-3448 1000);
PAINT GREEN (-3448 1000);
DISPLAY INVISIBLE (-3448 1000);
FORCEADD TAP..1
(-1725 1000);
FORCEPROP 3 LASTPIN (-1775 1000) SIG_NAME P5E_CPU0_P3_TX_BUF_C_DN<5>
J 0
(-1765 1010);
DISPLAY 0.659574 (-1765 1010);
PAINT MONO (-1765 1010);
DISPLAY INVISIBLE (-1765 1010);
FORCEPROP 1 LASTPIN (-1775 1000) BN 5
J 0
(-1787 1008);
DISPLAY 0.680851 (-1787 1008);
PAINT GREEN (-1787 1008);
FORCEPROP 2 LAST CDS_LIB standard
J 0
(-1725 1000);
DISPLAY INVISIBLE (-1725 1000);
FORCEPROP 1 LAST BODY_TYPE PLUMBING
J 0
(-1725 1050);
DISPLAY 0.872340 (-1725 1050);
PAINT GREEN (-1725 1050);
DISPLAY INVISIBLE (-1725 1050);
FORCEPROP 1 LAST HDL_TAP TRUE
J 0
(-1400 875);
DISPLAY 0.872340 (-1400 875);
DISPLAY INVISIBLE (-1400 875);
FORCEPROP 1 LAST PATH I30
J 0
(-1727 1000);
DISPLAY 0.872340 (-1727 1000);
PAINT GREEN (-1727 1000);
DISPLAY INVISIBLE (-1727 1000);
FORCEADD Q_CAP_DIFFBUS..2
R 2
(-2475 1200);
FORCEPROP 1 LAST LOCATION C6606
J 2
(-2200 1200);
DISPLAY 0.723404 (-2200 1200);
PAINT GREEN (-2200 1200);
FORCEPROP 2 LAST $SEC 1
J 2
(-2300 1275);
DISPLAY 0.680851 (-2300 1275);
PAINT MONO (-2300 1275);
DISPLAY INVISIBLE (-2300 1275);
FORCEPROP 2 LAST CDS_SEC 1
J 2
(-2300 1275);
DISPLAY 0.680851 (-2300 1275);
DISPLAY INVISIBLE (-2300 1275);
FORCEPROP 2 LASTPIN (-2400 1200) $PN 1
J 0
(-2390 1210);
DISPLAY 0.808511 (-2390 1210);
FORCEPROP 2 LASTPIN (-2550 1200) $PN 2
J 2
(-2560 1210);
DISPLAY 0.808511 (-2560 1210);
FORCEPROP 2 LAST VALUE DIFF BUS_0.22UF
J 2
(-2625 1200);
DISPLAY 0.553191 (-2625 1200);
FORCEPROP 2 LAST TOLERANCE 20%
J 2
(-2550 1250);
DISPLAY 0.553191 (-2550 1250);
DISPLAY INVISIBLE (-2550 1250);
FORCEPROP 2 LAST PACK_TYPE C0201
J 2
(-2650 1250);
DISPLAY 0.553191 (-2650 1250);
DISPLAY INVISIBLE (-2650 1250);
FORCEPROP 1 LAST MATERIAL X6S
J 2
(-2466 1279);
DISPLAY 0.574468 (-2466 1279);
PAINT GREEN (-2466 1279);
DISPLAY INVISIBLE (-2466 1279);
FORCEPROP 2 LAST VOLTAGE 6.3V
J 2
(-2825 1250);
DISPLAY 0.553191 (-2825 1250);
DISPLAY INVISIBLE (-2825 1250);
FORCEPROP 1 LAST PIN_NAMES_ROTATE TRUE
J 2
(-2475 1200);
DISPLAY 0.489362 (-2475 1200);
PAINT GREEN (-2475 1200);
DISPLAY INVISIBLE (-2475 1200);
FORCEPROP 1 LAST CDS_LMAN_SYM_OUTLINE -25,50,25,-50
J 2
(-2475 1200);
DISPLAY 0.468085 (-2475 1200);
PAINT GREEN (-2475 1200);
DISPLAY INVISIBLE (-2475 1200);
FORCEPROP 2 LAST CDS_LIB pure_quanta
J 2
(-2475 1200);
DISPLAY INVISIBLE (-2475 1200);
FORCEPROP 1 LAST PATH I31
J 2
(-2475 1200);
DISPLAY 0.723404 (-2475 1200);
DISPLAY INVISIBLE (-2475 1200);
FORCEPROP 1 LAST PART_NUMBER SP_CH4221MEE01
J 2
(-2591 1288);
DISPLAY 0.574468 (-2591 1288);
PAINT GREEN (-2591 1288);
DISPLAY INVISIBLE (-2591 1288);
FORCEPROP 1 LAST LOCATION C6606
J 0
(-2225 1275);
DISPLAY 1.021277 (-2225 1275);
DISPLAY INVISIBLE (-2225 1275);
FORCEADD Q_CAP_DIFFBUS..2
R 2
(-2475 1250);
FORCEPROP 1 LAST LOCATION C6605
J 2
(-2200 1250);
DISPLAY 0.723404 (-2200 1250);
PAINT GREEN (-2200 1250);
FORCEPROP 2 LAST $SEC 1
J 2
(-2300 1325);
DISPLAY 0.680851 (-2300 1325);
PAINT MONO (-2300 1325);
DISPLAY INVISIBLE (-2300 1325);
FORCEPROP 2 LAST CDS_SEC 1
J 2
(-2300 1325);
DISPLAY 0.680851 (-2300 1325);
DISPLAY INVISIBLE (-2300 1325);
FORCEPROP 2 LASTPIN (-2400 1250) $PN 1
J 0
(-2390 1260);
DISPLAY 0.808511 (-2390 1260);
FORCEPROP 2 LASTPIN (-2550 1250) $PN 2
J 2
(-2560 1260);
DISPLAY 0.808511 (-2560 1260);
FORCEPROP 2 LAST VALUE DIFF BUS_0.22UF
J 2
(-2625 1250);
DISPLAY 0.553191 (-2625 1250);
FORCEPROP 2 LAST TOLERANCE 20%
J 2
(-2550 1300);
DISPLAY 0.553191 (-2550 1300);
DISPLAY INVISIBLE (-2550 1300);
FORCEPROP 2 LAST PACK_TYPE C0201
J 2
(-2650 1300);
DISPLAY 0.553191 (-2650 1300);
DISPLAY INVISIBLE (-2650 1300);
FORCEPROP 1 LAST MATERIAL X6S
J 2
(-2466 1329);
DISPLAY 0.574468 (-2466 1329);
PAINT GREEN (-2466 1329);
DISPLAY INVISIBLE (-2466 1329);
FORCEPROP 2 LAST VOLTAGE 6.3V
J 2
(-2825 1300);
DISPLAY 0.553191 (-2825 1300);
DISPLAY INVISIBLE (-2825 1300);
FORCEPROP 1 LAST PIN_NAMES_ROTATE TRUE
J 2
(-2475 1250);
DISPLAY 0.489362 (-2475 1250);
PAINT GREEN (-2475 1250);
DISPLAY INVISIBLE (-2475 1250);
FORCEPROP 1 LAST CDS_LMAN_SYM_OUTLINE -25,50,25,-50
J 2
(-2475 1250);
DISPLAY 0.468085 (-2475 1250);
PAINT GREEN (-2475 1250);
DISPLAY INVISIBLE (-2475 1250);
FORCEPROP 2 LAST CDS_LIB pure_quanta
J 2
(-2475 1250);
DISPLAY INVISIBLE (-2475 1250);
FORCEPROP 1 LAST PATH I32
J 2
(-2475 1250);
DISPLAY 0.723404 (-2475 1250);
DISPLAY INVISIBLE (-2475 1250);
FORCEPROP 1 LAST PART_NUMBER SP_CH4221MEE01
J 2
(-2591 1338);
DISPLAY 0.574468 (-2591 1338);
PAINT GREEN (-2591 1338);
DISPLAY INVISIBLE (-2591 1338);
FORCEPROP 1 LAST LOCATION C6605
J 0
(-2225 1325);
DISPLAY 1.021277 (-2225 1325);
DISPLAY INVISIBLE (-2225 1325);
FORCEADD Q_CAP_DIFFBUS..2
R 2
(-2475 1400);
FORCEPROP 1 LAST LOCATION C6604
J 2
(-2200 1400);
DISPLAY 0.723404 (-2200 1400);
PAINT GREEN (-2200 1400);
FORCEPROP 2 LAST $SEC 1
J 2
(-2300 1475);
DISPLAY 0.680851 (-2300 1475);
PAINT MONO (-2300 1475);
DISPLAY INVISIBLE (-2300 1475);
FORCEPROP 2 LAST CDS_SEC 1
J 2
(-2300 1475);
DISPLAY 0.680851 (-2300 1475);
DISPLAY INVISIBLE (-2300 1475);
FORCEPROP 2 LASTPIN (-2400 1400) $PN 1
J 0
(-2390 1410);
DISPLAY 0.808511 (-2390 1410);
FORCEPROP 2 LASTPIN (-2550 1400) $PN 2
J 2
(-2560 1410);
DISPLAY 0.808511 (-2560 1410);
FORCEPROP 2 LAST VALUE DIFF BUS_0.22UF
J 2
(-2625 1400);
DISPLAY 0.553191 (-2625 1400);
FORCEPROP 2 LAST TOLERANCE 20%
J 2
(-2550 1450);
DISPLAY 0.553191 (-2550 1450);
DISPLAY INVISIBLE (-2550 1450);
FORCEPROP 2 LAST PACK_TYPE C0201
J 2
(-2650 1450);
DISPLAY 0.553191 (-2650 1450);
DISPLAY INVISIBLE (-2650 1450);
FORCEPROP 1 LAST MATERIAL X6S
J 2
(-2466 1479);
DISPLAY 0.574468 (-2466 1479);
PAINT GREEN (-2466 1479);
DISPLAY INVISIBLE (-2466 1479);
FORCEPROP 2 LAST VOLTAGE 6.3V
J 2
(-2825 1450);
DISPLAY 0.553191 (-2825 1450);
DISPLAY INVISIBLE (-2825 1450);
FORCEPROP 1 LAST PIN_NAMES_ROTATE TRUE
J 2
(-2475 1400);
DISPLAY 0.489362 (-2475 1400);
PAINT GREEN (-2475 1400);
DISPLAY INVISIBLE (-2475 1400);
FORCEPROP 2 LAST CDS_LIB pure_quanta
J 2
(-2475 1400);
DISPLAY INVISIBLE (-2475 1400);
FORCEPROP 1 LAST CDS_LMAN_SYM_OUTLINE -25,50,25,-50
J 2
(-2475 1400);
DISPLAY 0.468085 (-2475 1400);
PAINT GREEN (-2475 1400);
DISPLAY INVISIBLE (-2475 1400);
FORCEPROP 1 LAST PATH I33
J 2
(-2475 1400);
DISPLAY 0.723404 (-2475 1400);
DISPLAY INVISIBLE (-2475 1400);
FORCEPROP 1 LAST PART_NUMBER SP_CH4221MEE01
J 2
(-2591 1488);
DISPLAY 0.574468 (-2591 1488);
PAINT GREEN (-2591 1488);
DISPLAY INVISIBLE (-2591 1488);
FORCEPROP 1 LAST LOCATION C6604
J 0
(-2225 1475);
DISPLAY 1.021277 (-2225 1475);
DISPLAY INVISIBLE (-2225 1475);
FORCEADD Q_CAP_DIFFBUS..2
R 2
(-2475 1450);
FORCEPROP 1 LAST LOCATION C6603
J 2
(-2200 1450);
DISPLAY 0.723404 (-2200 1450);
PAINT GREEN (-2200 1450);
FORCEPROP 2 LAST $SEC 1
J 2
(-2300 1525);
DISPLAY 0.680851 (-2300 1525);
PAINT MONO (-2300 1525);
DISPLAY INVISIBLE (-2300 1525);
FORCEPROP 2 LAST CDS_SEC 1
J 2
(-2300 1525);
DISPLAY 0.680851 (-2300 1525);
DISPLAY INVISIBLE (-2300 1525);
FORCEPROP 2 LASTPIN (-2400 1450) $PN 1
J 0
(-2390 1460);
DISPLAY 0.808511 (-2390 1460);
FORCEPROP 2 LASTPIN (-2550 1450) $PN 2
J 2
(-2560 1460);
DISPLAY 0.808511 (-2560 1460);
FORCEPROP 2 LAST VALUE DIFF BUS_0.22UF
J 2
(-2625 1450);
DISPLAY 0.553191 (-2625 1450);
FORCEPROP 2 LAST TOLERANCE 20%
J 2
(-2550 1500);
DISPLAY 0.553191 (-2550 1500);
DISPLAY INVISIBLE (-2550 1500);
FORCEPROP 2 LAST PACK_TYPE C0201
J 2
(-2650 1500);
DISPLAY 0.553191 (-2650 1500);
DISPLAY INVISIBLE (-2650 1500);
FORCEPROP 1 LAST MATERIAL X6S
J 2
(-2466 1529);
DISPLAY 0.574468 (-2466 1529);
PAINT GREEN (-2466 1529);
DISPLAY INVISIBLE (-2466 1529);
FORCEPROP 2 LAST VOLTAGE 6.3V
J 2
(-2825 1500);
DISPLAY 0.553191 (-2825 1500);
DISPLAY INVISIBLE (-2825 1500);
FORCEPROP 1 LAST PIN_NAMES_ROTATE TRUE
J 2
(-2475 1450);
DISPLAY 0.489362 (-2475 1450);
PAINT GREEN (-2475 1450);
DISPLAY INVISIBLE (-2475 1450);
FORCEPROP 2 LAST CDS_LIB pure_quanta
J 2
(-2475 1450);
DISPLAY INVISIBLE (-2475 1450);
FORCEPROP 1 LAST CDS_LMAN_SYM_OUTLINE -25,50,25,-50
J 2
(-2475 1450);
DISPLAY 0.468085 (-2475 1450);
PAINT GREEN (-2475 1450);
DISPLAY INVISIBLE (-2475 1450);
FORCEPROP 1 LAST PATH I34
J 2
(-2475 1450);
DISPLAY 0.723404 (-2475 1450);
DISPLAY INVISIBLE (-2475 1450);
FORCEPROP 1 LAST PART_NUMBER SP_CH4221MEE01
J 2
(-2591 1538);
DISPLAY 0.574468 (-2591 1538);
PAINT GREEN (-2591 1538);
DISPLAY INVISIBLE (-2591 1538);
FORCEPROP 1 LAST LOCATION C6603
J 0
(-2225 1525);
DISPLAY 1.021277 (-2225 1525);
DISPLAY INVISIBLE (-2225 1525);
FORCEADD Q_CAP_DIFFBUS..2
R 2
(-2475 1600);
FORCEPROP 1 LAST LOCATION C6602
J 2
(-2200 1600);
DISPLAY 0.723404 (-2200 1600);
PAINT GREEN (-2200 1600);
FORCEPROP 2 LAST $SEC 1
J 2
(-2300 1675);
DISPLAY 0.680851 (-2300 1675);
PAINT MONO (-2300 1675);
DISPLAY INVISIBLE (-2300 1675);
FORCEPROP 2 LAST CDS_SEC 1
J 2
(-2300 1675);
DISPLAY 0.680851 (-2300 1675);
DISPLAY INVISIBLE (-2300 1675);
FORCEPROP 2 LASTPIN (-2400 1600) $PN 1
J 0
(-2390 1610);
DISPLAY 0.808511 (-2390 1610);
FORCEPROP 2 LASTPIN (-2550 1600) $PN 2
J 2
(-2560 1610);
DISPLAY 0.808511 (-2560 1610);
FORCEPROP 2 LAST VALUE DIFF BUS_0.22UF
J 2
(-2625 1600);
DISPLAY 0.553191 (-2625 1600);
FORCEPROP 2 LAST TOLERANCE 20%
J 2
(-2550 1650);
DISPLAY 0.553191 (-2550 1650);
DISPLAY INVISIBLE (-2550 1650);
FORCEPROP 2 LAST PACK_TYPE C0201
J 2
(-2650 1650);
DISPLAY 0.553191 (-2650 1650);
DISPLAY INVISIBLE (-2650 1650);
FORCEPROP 1 LAST MATERIAL X6S
J 2
(-2466 1679);
DISPLAY 0.574468 (-2466 1679);
PAINT GREEN (-2466 1679);
DISPLAY INVISIBLE (-2466 1679);
FORCEPROP 2 LAST VOLTAGE 6.3V
J 2
(-2825 1650);
DISPLAY 0.553191 (-2825 1650);
DISPLAY INVISIBLE (-2825 1650);
FORCEPROP 1 LAST PIN_NAMES_ROTATE TRUE
J 2
(-2475 1600);
DISPLAY 0.489362 (-2475 1600);
PAINT GREEN (-2475 1600);
DISPLAY INVISIBLE (-2475 1600);
FORCEPROP 2 LAST CDS_LIB pure_quanta
J 2
(-2475 1600);
DISPLAY INVISIBLE (-2475 1600);
FORCEPROP 1 LAST CDS_LMAN_SYM_OUTLINE -25,50,25,-50
J 2
(-2475 1600);
DISPLAY 0.468085 (-2475 1600);
PAINT GREEN (-2475 1600);
DISPLAY INVISIBLE (-2475 1600);
FORCEPROP 1 LAST PATH I35
J 2
(-2475 1600);
DISPLAY 0.723404 (-2475 1600);
DISPLAY INVISIBLE (-2475 1600);
FORCEPROP 1 LAST PART_NUMBER SP_CH4221MEE01
J 2
(-2591 1688);
DISPLAY 0.574468 (-2591 1688);
PAINT GREEN (-2591 1688);
DISPLAY INVISIBLE (-2591 1688);
FORCEPROP 1 LAST LOCATION C6602
J 0
(-2225 1675);
DISPLAY 1.021277 (-2225 1675);
DISPLAY INVISIBLE (-2225 1675);
FORCEADD Q_CAP_DIFFBUS..2
R 2
(-2475 1650);
FORCEPROP 1 LAST LOCATION C6601
J 2
(-2200 1650);
DISPLAY 0.723404 (-2200 1650);
PAINT GREEN (-2200 1650);
FORCEPROP 2 LAST $SEC 1
J 2
(-2300 1725);
DISPLAY 0.680851 (-2300 1725);
PAINT MONO (-2300 1725);
DISPLAY INVISIBLE (-2300 1725);
FORCEPROP 2 LAST CDS_SEC 1
J 2
(-2300 1725);
DISPLAY 0.680851 (-2300 1725);
DISPLAY INVISIBLE (-2300 1725);
FORCEPROP 2 LASTPIN (-2400 1650) $PN 1
J 0
(-2390 1660);
DISPLAY 0.808511 (-2390 1660);
FORCEPROP 2 LASTPIN (-2550 1650) $PN 2
J 2
(-2560 1660);
DISPLAY 0.808511 (-2560 1660);
FORCEPROP 2 LAST VALUE DIFF BUS_0.22UF
J 2
(-2625 1650);
DISPLAY 0.553191 (-2625 1650);
FORCEPROP 2 LAST TOLERANCE 20%
J 2
(-2550 1700);
DISPLAY 0.553191 (-2550 1700);
DISPLAY INVISIBLE (-2550 1700);
FORCEPROP 2 LAST PACK_TYPE C0201
J 2
(-2650 1700);
DISPLAY 0.553191 (-2650 1700);
DISPLAY INVISIBLE (-2650 1700);
FORCEPROP 1 LAST MATERIAL X6S
J 2
(-2466 1729);
DISPLAY 0.574468 (-2466 1729);
PAINT GREEN (-2466 1729);
DISPLAY INVISIBLE (-2466 1729);
FORCEPROP 2 LAST VOLTAGE 6.3V
J 2
(-2825 1700);
DISPLAY 0.553191 (-2825 1700);
DISPLAY INVISIBLE (-2825 1700);
FORCEPROP 1 LAST PIN_NAMES_ROTATE TRUE
J 2
(-2475 1650);
DISPLAY 0.489362 (-2475 1650);
PAINT GREEN (-2475 1650);
DISPLAY INVISIBLE (-2475 1650);
FORCEPROP 2 LAST CDS_LIB pure_quanta
J 2
(-2475 1650);
DISPLAY INVISIBLE (-2475 1650);
FORCEPROP 1 LAST CDS_LMAN_SYM_OUTLINE -25,50,25,-50
J 2
(-2475 1650);
DISPLAY 0.468085 (-2475 1650);
PAINT GREEN (-2475 1650);
DISPLAY INVISIBLE (-2475 1650);
FORCEPROP 1 LAST PATH I36
J 2
(-2475 1650);
DISPLAY 0.723404 (-2475 1650);
DISPLAY INVISIBLE (-2475 1650);
FORCEPROP 1 LAST PART_NUMBER SP_CH4221MEE01
J 2
(-2591 1738);
DISPLAY 0.574468 (-2591 1738);
PAINT GREEN (-2591 1738);
DISPLAY INVISIBLE (-2591 1738);
FORCEPROP 1 LAST LOCATION C6601
J 0
(-2225 1725);
DISPLAY 1.021277 (-2225 1725);
DISPLAY INVISIBLE (-2225 1725);
FORCEADD Q_CAP_DIFFBUS..2
R 2
(-2475 1800);
FORCEPROP 1 LAST LOCATION C6600
J 2
(-2175 1800);
DISPLAY 0.723404 (-2175 1800);
PAINT GREEN (-2175 1800);
FORCEPROP 2 LAST $SEC 1
J 2
(-2300 1875);
DISPLAY 0.680851 (-2300 1875);
PAINT MONO (-2300 1875);
DISPLAY INVISIBLE (-2300 1875);
FORCEPROP 2 LAST CDS_SEC 1
J 2
(-2300 1875);
DISPLAY 0.680851 (-2300 1875);
DISPLAY INVISIBLE (-2300 1875);
FORCEPROP 2 LASTPIN (-2400 1800) $PN 1
J 0
(-2390 1810);
DISPLAY 0.808511 (-2390 1810);
FORCEPROP 2 LASTPIN (-2550 1800) $PN 2
J 2
(-2560 1810);
DISPLAY 0.808511 (-2560 1810);
FORCEPROP 2 LAST VALUE DIFF BUS_0.22UF
J 2
(-2625 1800);
DISPLAY 0.553191 (-2625 1800);
FORCEPROP 2 LAST TOLERANCE 20%
J 2
(-2550 1850);
DISPLAY 0.553191 (-2550 1850);
DISPLAY INVISIBLE (-2550 1850);
FORCEPROP 2 LAST PACK_TYPE C0201
J 2
(-2650 1850);
DISPLAY 0.553191 (-2650 1850);
DISPLAY INVISIBLE (-2650 1850);
FORCEPROP 1 LAST MATERIAL X6S
J 2
(-2466 1879);
DISPLAY 0.574468 (-2466 1879);
PAINT GREEN (-2466 1879);
DISPLAY INVISIBLE (-2466 1879);
FORCEPROP 2 LAST VOLTAGE 6.3V
J 2
(-2825 1850);
DISPLAY 0.553191 (-2825 1850);
DISPLAY INVISIBLE (-2825 1850);
FORCEPROP 1 LAST PIN_NAMES_ROTATE TRUE
J 2
(-2475 1800);
DISPLAY 0.489362 (-2475 1800);
PAINT GREEN (-2475 1800);
DISPLAY INVISIBLE (-2475 1800);
FORCEPROP 2 LAST CDS_LIB pure_quanta
J 2
(-2475 1800);
DISPLAY INVISIBLE (-2475 1800);
FORCEPROP 1 LAST CDS_LMAN_SYM_OUTLINE -25,50,25,-50
J 2
(-2475 1800);
DISPLAY 0.468085 (-2475 1800);
PAINT GREEN (-2475 1800);
DISPLAY INVISIBLE (-2475 1800);
FORCEPROP 1 LAST PATH I37
J 2
(-2475 1800);
DISPLAY 0.723404 (-2475 1800);
DISPLAY INVISIBLE (-2475 1800);
FORCEPROP 1 LAST PART_NUMBER SP_CH4221MEE01
J 2
(-2591 1888);
DISPLAY 0.574468 (-2591 1888);
PAINT GREEN (-2591 1888);
DISPLAY INVISIBLE (-2591 1888);
FORCEPROP 1 LAST LOCATION C6600
J 0
(-2225 1875);
DISPLAY 1.021277 (-2225 1875);
DISPLAY INVISIBLE (-2225 1875);
FORCEADD Q_CAP_DIFFBUS..2
R 2
(-2475 1850);
FORCEPROP 1 LAST LOCATION C6599
J 2
(-2175 1850);
DISPLAY 0.723404 (-2175 1850);
PAINT GREEN (-2175 1850);
FORCEPROP 2 LAST $SEC 1
J 2
(-2300 1925);
DISPLAY 0.680851 (-2300 1925);
PAINT MONO (-2300 1925);
DISPLAY INVISIBLE (-2300 1925);
FORCEPROP 2 LAST CDS_SEC 1
J 2
(-2300 1925);
DISPLAY 0.680851 (-2300 1925);
DISPLAY INVISIBLE (-2300 1925);
FORCEPROP 2 LASTPIN (-2400 1850) $PN 1
J 0
(-2390 1860);
DISPLAY 0.808511 (-2390 1860);
FORCEPROP 2 LASTPIN (-2550 1850) $PN 2
J 2
(-2560 1860);
DISPLAY 0.808511 (-2560 1860);
FORCEPROP 2 LAST VALUE DIFF BUS_0.22UF
J 2
(-2625 1850);
DISPLAY 0.553191 (-2625 1850);
FORCEPROP 1 LAST CDS_LMAN_SYM_OUTLINE -25,50,25,-50
J 2
(-2475 1850);
DISPLAY 0.468085 (-2475 1850);
PAINT GREEN (-2475 1850);
DISPLAY INVISIBLE (-2475 1850);
FORCEPROP 2 LAST CDS_LIB pure_quanta
J 2
(-2475 1850);
DISPLAY INVISIBLE (-2475 1850);
FORCEPROP 1 LAST PIN_NAMES_ROTATE TRUE
J 2
(-2475 1850);
DISPLAY 0.489362 (-2475 1850);
PAINT GREEN (-2475 1850);
DISPLAY INVISIBLE (-2475 1850);
FORCEPROP 2 LAST VOLTAGE 6.3V
J 2
(-2825 1900);
DISPLAY 0.553191 (-2825 1900);
DISPLAY INVISIBLE (-2825 1900);
FORCEPROP 1 LAST MATERIAL X6S
J 2
(-2466 1929);
DISPLAY 0.574468 (-2466 1929);
PAINT GREEN (-2466 1929);
DISPLAY INVISIBLE (-2466 1929);
FORCEPROP 2 LAST PACK_TYPE C0201
J 2
(-2650 1900);
DISPLAY 0.553191 (-2650 1900);
DISPLAY INVISIBLE (-2650 1900);
FORCEPROP 2 LAST TOLERANCE 20%
J 2
(-2550 1900);
DISPLAY 0.553191 (-2550 1900);
DISPLAY INVISIBLE (-2550 1900);
FORCEPROP 1 LAST PATH I38
J 2
(-2475 1850);
DISPLAY 0.723404 (-2475 1850);
DISPLAY INVISIBLE (-2475 1850);
FORCEPROP 1 LAST PART_NUMBER SP_CH4221MEE01
J 2
(-2591 1938);
DISPLAY 0.574468 (-2591 1938);
PAINT GREEN (-2591 1938);
DISPLAY INVISIBLE (-2591 1938);
FORCEPROP 1 LAST LOCATION C6599
J 0
(-2225 1925);
DISPLAY 1.021277 (-2225 1925);
DISPLAY INVISIBLE (-2225 1925);
FORCEADD Q_CAP_DIFFBUS..2
R 2
(-2475 2000);
FORCEPROP 1 LAST LOCATION C6598
J 2
(-2175 2000);
DISPLAY 0.723404 (-2175 2000);
PAINT GREEN (-2175 2000);
FORCEPROP 2 LAST $SEC 1
J 2
(-2300 2075);
DISPLAY 0.680851 (-2300 2075);
PAINT MONO (-2300 2075);
DISPLAY INVISIBLE (-2300 2075);
FORCEPROP 2 LAST CDS_SEC 1
J 2
(-2300 2075);
DISPLAY 0.680851 (-2300 2075);
DISPLAY INVISIBLE (-2300 2075);
FORCEPROP 2 LASTPIN (-2400 2000) $PN 1
J 0
(-2390 2010);
DISPLAY 0.808511 (-2390 2010);
FORCEPROP 2 LASTPIN (-2550 2000) $PN 2
J 2
(-2560 2010);
DISPLAY 0.808511 (-2560 2010);
FORCEPROP 2 LAST VALUE DIFF BUS_0.22UF
J 2
(-2625 2000);
DISPLAY 0.553191 (-2625 2000);
FORCEPROP 2 LAST TOLERANCE 20%
J 2
(-2550 2050);
DISPLAY 0.553191 (-2550 2050);
DISPLAY INVISIBLE (-2550 2050);
FORCEPROP 2 LAST PACK_TYPE C0201
J 2
(-2650 2050);
DISPLAY 0.553191 (-2650 2050);
DISPLAY INVISIBLE (-2650 2050);
FORCEPROP 1 LAST MATERIAL X6S
J 2
(-2466 2079);
DISPLAY 0.574468 (-2466 2079);
PAINT GREEN (-2466 2079);
DISPLAY INVISIBLE (-2466 2079);
FORCEPROP 2 LAST VOLTAGE 6.3V
J 2
(-2825 2050);
DISPLAY 0.553191 (-2825 2050);
DISPLAY INVISIBLE (-2825 2050);
FORCEPROP 1 LAST PIN_NAMES_ROTATE TRUE
J 2
(-2475 2000);
DISPLAY 0.489362 (-2475 2000);
PAINT GREEN (-2475 2000);
DISPLAY INVISIBLE (-2475 2000);
FORCEPROP 2 LAST CDS_LIB pure_quanta
J 2
(-2475 2000);
DISPLAY INVISIBLE (-2475 2000);
FORCEPROP 1 LAST CDS_LMAN_SYM_OUTLINE -25,50,25,-50
J 2
(-2475 2000);
DISPLAY 0.468085 (-2475 2000);
PAINT GREEN (-2475 2000);
DISPLAY INVISIBLE (-2475 2000);
FORCEPROP 1 LAST PATH I39
J 2
(-2475 2000);
DISPLAY 0.723404 (-2475 2000);
DISPLAY INVISIBLE (-2475 2000);
FORCEPROP 1 LAST PART_NUMBER SP_CH4221MEE01
J 2
(-2591 2088);
DISPLAY 0.574468 (-2591 2088);
PAINT GREEN (-2591 2088);
DISPLAY INVISIBLE (-2591 2088);
FORCEPROP 1 LAST LOCATION C6598
J 0
(-2225 2075);
DISPLAY 1.021277 (-2225 2075);
DISPLAY INVISIBLE (-2225 2075);
FORCEADD TAP..1
R 2
(-3450 800);
FORCEPROP 3 LASTPIN (-3400 800) SIG_NAME P5E_CPU0_P3_TX_BUF_DN<6>
J 0
(-3390 810);
DISPLAY 0.659574 (-3390 810);
PAINT MONO (-3390 810);
DISPLAY INVISIBLE (-3390 810);
FORCEPROP 1 LASTPIN (-3400 800) BN 6
J 2
(-3388 808);
DISPLAY 0.680851 (-3388 808);
PAINT GREEN (-3388 808);
FORCEPROP 2 LAST CDS_LIB standard
J 0
(-3450 800);
DISPLAY INVISIBLE (-3450 800);
FORCEPROP 1 LAST BODY_TYPE PLUMBING
J 2
(-3450 850);
DISPLAY 0.872340 (-3450 850);
PAINT GREEN (-3450 850);
DISPLAY INVISIBLE (-3450 850);
FORCEPROP 1 LAST HDL_TAP TRUE
J 2
(-3775 675);
DISPLAY 0.872340 (-3775 675);
DISPLAY INVISIBLE (-3775 675);
FORCEPROP 1 LAST PATH I4
J 2
(-3448 800);
DISPLAY 0.872340 (-3448 800);
PAINT GREEN (-3448 800);
DISPLAY INVISIBLE (-3448 800);
FORCEADD Q_CAP_DIFFBUS..2
R 2
(-2475 2050);
FORCEPROP 1 LAST LOCATION C6597
J 2
(-2175 2050);
DISPLAY 0.723404 (-2175 2050);
PAINT GREEN (-2175 2050);
FORCEPROP 2 LAST $SEC 1
J 2
(-2300 2125);
DISPLAY 0.680851 (-2300 2125);
PAINT MONO (-2300 2125);
DISPLAY INVISIBLE (-2300 2125);
FORCEPROP 2 LAST CDS_SEC 1
J 2
(-2300 2125);
DISPLAY 0.680851 (-2300 2125);
DISPLAY INVISIBLE (-2300 2125);
FORCEPROP 2 LASTPIN (-2400 2050) $PN 1
J 0
(-2390 2060);
DISPLAY 0.808511 (-2390 2060);
FORCEPROP 2 LASTPIN (-2550 2050) $PN 2
J 2
(-2560 2060);
DISPLAY 0.808511 (-2560 2060);
FORCEPROP 2 LAST VALUE DIFF BUS_0.22UF
J 2
(-2625 2050);
DISPLAY 0.553191 (-2625 2050);
FORCEPROP 2 LAST TOLERANCE 20%
J 2
(-2425 2200);
DISPLAY 0.553191 (-2425 2200);
PAINT GREEN (-2425 2200);
FORCEPROP 2 LAST VOLTAGE 6.3V
J 2
(-2300 2200);
DISPLAY 0.553191 (-2300 2200);
PAINT GREEN (-2300 2200);
FORCEPROP 1 LAST MATERIAL X6S
J 2
(-2566 2254);
DISPLAY 0.574468 (-2566 2254);
PAINT GREEN (-2566 2254);
FORCEPROP 2 LAST PACK_TYPE C0201
J 2
(-2525 2200);
DISPLAY 0.553191 (-2525 2200);
PAINT GREEN (-2525 2200);
FORCEPROP 1 LAST PIN_NAMES_ROTATE TRUE
J 2
(-2475 2050);
DISPLAY 0.489362 (-2475 2050);
PAINT GREEN (-2475 2050);
DISPLAY INVISIBLE (-2475 2050);
FORCEPROP 1 LAST CDS_LMAN_SYM_OUTLINE -25,50,25,-50
J 2
(-2475 2050);
DISPLAY 0.468085 (-2475 2050);
PAINT GREEN (-2475 2050);
DISPLAY INVISIBLE (-2475 2050);
FORCEPROP 2 LAST CDS_LIB pure_quanta
J 2
(-2475 2050);
DISPLAY INVISIBLE (-2475 2050);
FORCEPROP 1 LAST PATH I40
J 2
(-2475 2050);
DISPLAY 0.723404 (-2475 2050);
DISPLAY INVISIBLE (-2475 2050);
FORCEPROP 1 LAST PART_NUMBER SP_CH4221MEE01
J 2
(-2291 2138);
DISPLAY 0.574468 (-2291 2138);
PAINT GREEN (-2291 2138);
DISPLAY INVISIBLE (-2291 2138);
FORCEPROP 1 LAST LOCATION C6597
J 0
(-2225 2125);
DISPLAY 1.021277 (-2225 2125);
DISPLAY INVISIBLE (-2225 2125);
FORCEADD TAP..1
(-1925 1450);
FORCEPROP 3 LASTPIN (-1975 1450) SIG_NAME P5E_CPU0_P3_TX_BUF_C_DP<3>
J 0
(-1965 1460);
DISPLAY 0.659574 (-1965 1460);
PAINT MONO (-1965 1460);
DISPLAY INVISIBLE (-1965 1460);
FORCEPROP 1 LASTPIN (-1975 1450) BN 3
J 0
(-1987 1458);
DISPLAY 0.680851 (-1987 1458);
PAINT GREEN (-1987 1458);
FORCEPROP 2 LAST CDS_LIB standard
J 0
(-1925 1450);
DISPLAY INVISIBLE (-1925 1450);
FORCEPROP 1 LAST BODY_TYPE PLUMBING
J 0
(-1925 1500);
DISPLAY 0.872340 (-1925 1500);
PAINT GREEN (-1925 1500);
DISPLAY INVISIBLE (-1925 1500);
FORCEPROP 1 LAST HDL_TAP TRUE
J 0
(-1600 1325);
DISPLAY 0.872340 (-1600 1325);
DISPLAY INVISIBLE (-1600 1325);
FORCEPROP 1 LAST PATH I41
J 0
(-1927 1450);
DISPLAY 0.872340 (-1927 1450);
PAINT GREEN (-1927 1450);
DISPLAY INVISIBLE (-1927 1450);
FORCEADD TAP..1
(-1925 1250);
FORCEPROP 3 LASTPIN (-1975 1250) SIG_NAME P5E_CPU0_P3_TX_BUF_C_DP<4>
J 0
(-1965 1260);
DISPLAY 0.659574 (-1965 1260);
PAINT MONO (-1965 1260);
DISPLAY INVISIBLE (-1965 1260);
FORCEPROP 1 LASTPIN (-1975 1250) BN 4
J 0
(-1987 1258);
DISPLAY 0.680851 (-1987 1258);
PAINT GREEN (-1987 1258);
FORCEPROP 2 LAST CDS_LIB standard
J 0
(-1925 1250);
DISPLAY INVISIBLE (-1925 1250);
FORCEPROP 1 LAST BODY_TYPE PLUMBING
J 0
(-1925 1300);
DISPLAY 0.872340 (-1925 1300);
PAINT GREEN (-1925 1300);
DISPLAY INVISIBLE (-1925 1300);
FORCEPROP 1 LAST HDL_TAP TRUE
J 0
(-1600 1125);
DISPLAY 0.872340 (-1600 1125);
DISPLAY INVISIBLE (-1600 1125);
FORCEPROP 1 LAST PATH I42
J 0
(-1927 1250);
DISPLAY 0.872340 (-1927 1250);
PAINT GREEN (-1927 1250);
DISPLAY INVISIBLE (-1927 1250);
FORCEADD TAP..1
(-1725 1200);
FORCEPROP 3 LASTPIN (-1775 1200) SIG_NAME P5E_CPU0_P3_TX_BUF_C_DN<4>
J 0
(-1765 1210);
DISPLAY 0.659574 (-1765 1210);
PAINT MONO (-1765 1210);
DISPLAY INVISIBLE (-1765 1210);
FORCEPROP 1 LASTPIN (-1775 1200) BN 4
J 0
(-1787 1208);
DISPLAY 0.680851 (-1787 1208);
PAINT GREEN (-1787 1208);
FORCEPROP 2 LAST CDS_LIB standard
J 0
(-1725 1200);
DISPLAY INVISIBLE (-1725 1200);
FORCEPROP 1 LAST BODY_TYPE PLUMBING
J 0
(-1725 1250);
DISPLAY 0.872340 (-1725 1250);
PAINT GREEN (-1725 1250);
DISPLAY INVISIBLE (-1725 1250);
FORCEPROP 1 LAST HDL_TAP TRUE
J 0
(-1400 1075);
DISPLAY 0.872340 (-1400 1075);
DISPLAY INVISIBLE (-1400 1075);
FORCEPROP 1 LAST PATH I43
J 0
(-1727 1200);
DISPLAY 0.872340 (-1727 1200);
PAINT GREEN (-1727 1200);
DISPLAY INVISIBLE (-1727 1200);
FORCEADD TAP..1
(-1725 1400);
FORCEPROP 3 LASTPIN (-1775 1400) SIG_NAME P5E_CPU0_P3_TX_BUF_C_DN<3>
J 0
(-1765 1410);
DISPLAY 0.659574 (-1765 1410);
PAINT MONO (-1765 1410);
DISPLAY INVISIBLE (-1765 1410);
FORCEPROP 1 LASTPIN (-1775 1400) BN 3
J 0
(-1787 1408);
DISPLAY 0.680851 (-1787 1408);
PAINT GREEN (-1787 1408);
FORCEPROP 2 LAST CDS_LIB standard
J 0
(-1725 1400);
DISPLAY INVISIBLE (-1725 1400);
FORCEPROP 1 LAST BODY_TYPE PLUMBING
J 0
(-1725 1450);
DISPLAY 0.872340 (-1725 1450);
PAINT GREEN (-1725 1450);
DISPLAY INVISIBLE (-1725 1450);
FORCEPROP 1 LAST HDL_TAP TRUE
J 0
(-1400 1275);
DISPLAY 0.872340 (-1400 1275);
DISPLAY INVISIBLE (-1400 1275);
FORCEPROP 1 LAST PATH I44
J 0
(-1727 1400);
DISPLAY 0.872340 (-1727 1400);
PAINT GREEN (-1727 1400);
DISPLAY INVISIBLE (-1727 1400);
FORCEADD TAP..1
(-1925 2050);
FORCEPROP 3 LASTPIN (-1975 2050) SIG_NAME P5E_CPU0_P3_TX_BUF_C_DP<0>
J 0
(-1965 2060);
DISPLAY 0.659574 (-1965 2060);
PAINT MONO (-1965 2060);
DISPLAY INVISIBLE (-1965 2060);
FORCEPROP 1 LASTPIN (-1975 2050) BN 0
J 0
(-1987 2058);
DISPLAY 0.680851 (-1987 2058);
PAINT GREEN (-1987 2058);
FORCEPROP 2 LAST CDS_LIB standard
J 0
(-1925 2050);
DISPLAY INVISIBLE (-1925 2050);
FORCEPROP 1 LAST BODY_TYPE PLUMBING
J 0
(-1925 2100);
DISPLAY 0.872340 (-1925 2100);
PAINT GREEN (-1925 2100);
DISPLAY INVISIBLE (-1925 2100);
FORCEPROP 1 LAST HDL_TAP TRUE
J 0
(-1600 1925);
DISPLAY 0.872340 (-1600 1925);
DISPLAY INVISIBLE (-1600 1925);
FORCEPROP 1 LAST PATH I45
J 0
(-1927 2050);
DISPLAY 0.872340 (-1927 2050);
PAINT GREEN (-1927 2050);
DISPLAY INVISIBLE (-1927 2050);
FORCEADD TAP..1
(-1925 1850);
FORCEPROP 3 LASTPIN (-1975 1850) SIG_NAME P5E_CPU0_P3_TX_BUF_C_DP<1>
J 0
(-1965 1860);
DISPLAY 0.659574 (-1965 1860);
PAINT MONO (-1965 1860);
DISPLAY INVISIBLE (-1965 1860);
FORCEPROP 1 LASTPIN (-1975 1850) BN 1
J 0
(-1987 1858);
DISPLAY 0.680851 (-1987 1858);
PAINT GREEN (-1987 1858);
FORCEPROP 2 LAST CDS_LIB standard
J 0
(-1925 1850);
DISPLAY INVISIBLE (-1925 1850);
FORCEPROP 1 LAST BODY_TYPE PLUMBING
J 0
(-1925 1900);
DISPLAY 0.872340 (-1925 1900);
PAINT GREEN (-1925 1900);
DISPLAY INVISIBLE (-1925 1900);
FORCEPROP 1 LAST HDL_TAP TRUE
J 0
(-1600 1725);
DISPLAY 0.872340 (-1600 1725);
DISPLAY INVISIBLE (-1600 1725);
FORCEPROP 1 LAST PATH I46
J 0
(-1927 1850);
DISPLAY 0.872340 (-1927 1850);
PAINT GREEN (-1927 1850);
DISPLAY INVISIBLE (-1927 1850);
FORCEADD TAP..1
(-1925 1650);
FORCEPROP 3 LASTPIN (-1975 1650) SIG_NAME P5E_CPU0_P3_TX_BUF_C_DP<2>
J 0
(-1965 1660);
DISPLAY 0.659574 (-1965 1660);
PAINT MONO (-1965 1660);
DISPLAY INVISIBLE (-1965 1660);
FORCEPROP 1 LASTPIN (-1975 1650) BN 2
J 0
(-1987 1658);
DISPLAY 0.680851 (-1987 1658);
PAINT GREEN (-1987 1658);
FORCEPROP 2 LAST CDS_LIB standard
J 0
(-1925 1650);
DISPLAY INVISIBLE (-1925 1650);
FORCEPROP 1 LAST BODY_TYPE PLUMBING
J 0
(-1925 1700);
DISPLAY 0.872340 (-1925 1700);
PAINT GREEN (-1925 1700);
DISPLAY INVISIBLE (-1925 1700);
FORCEPROP 1 LAST HDL_TAP TRUE
J 0
(-1600 1525);
DISPLAY 0.872340 (-1600 1525);
DISPLAY INVISIBLE (-1600 1525);
FORCEPROP 1 LAST PATH I47
J 0
(-1927 1650);
DISPLAY 0.872340 (-1927 1650);
PAINT GREEN (-1927 1650);
DISPLAY INVISIBLE (-1927 1650);
FORCEADD TAP..1
(-1725 1600);
FORCEPROP 3 LASTPIN (-1775 1600) SIG_NAME P5E_CPU0_P3_TX_BUF_C_DN<2>
J 0
(-1765 1610);
DISPLAY 0.659574 (-1765 1610);
PAINT MONO (-1765 1610);
DISPLAY INVISIBLE (-1765 1610);
FORCEPROP 1 LASTPIN (-1775 1600) BN 2
J 0
(-1787 1608);
DISPLAY 0.680851 (-1787 1608);
PAINT GREEN (-1787 1608);
FORCEPROP 2 LAST CDS_LIB standard
J 0
(-1725 1600);
DISPLAY INVISIBLE (-1725 1600);
FORCEPROP 1 LAST BODY_TYPE PLUMBING
J 0
(-1725 1650);
DISPLAY 0.872340 (-1725 1650);
PAINT GREEN (-1725 1650);
DISPLAY INVISIBLE (-1725 1650);
FORCEPROP 1 LAST HDL_TAP TRUE
J 0
(-1400 1475);
DISPLAY 0.872340 (-1400 1475);
DISPLAY INVISIBLE (-1400 1475);
FORCEPROP 1 LAST PATH I48
J 0
(-1727 1600);
DISPLAY 0.872340 (-1727 1600);
PAINT GREEN (-1727 1600);
DISPLAY INVISIBLE (-1727 1600);
FORCEADD TAP..1
(-1725 1800);
FORCEPROP 3 LASTPIN (-1775 1800) SIG_NAME P5E_CPU0_P3_TX_BUF_C_DN<1>
J 0
(-1765 1810);
DISPLAY 0.659574 (-1765 1810);
PAINT MONO (-1765 1810);
DISPLAY INVISIBLE (-1765 1810);
FORCEPROP 1 LASTPIN (-1775 1800) BN 1
J 0
(-1787 1808);
DISPLAY 0.680851 (-1787 1808);
PAINT GREEN (-1787 1808);
FORCEPROP 2 LAST CDS_LIB standard
J 0
(-1725 1800);
DISPLAY INVISIBLE (-1725 1800);
FORCEPROP 1 LAST BODY_TYPE PLUMBING
J 0
(-1725 1850);
DISPLAY 0.872340 (-1725 1850);
PAINT GREEN (-1725 1850);
DISPLAY INVISIBLE (-1725 1850);
FORCEPROP 1 LAST HDL_TAP TRUE
J 0
(-1400 1675);
DISPLAY 0.872340 (-1400 1675);
DISPLAY INVISIBLE (-1400 1675);
FORCEPROP 1 LAST PATH I49
J 0
(-1727 1800);
DISPLAY 0.872340 (-1727 1800);
PAINT GREEN (-1727 1800);
DISPLAY INVISIBLE (-1727 1800);
FORCEADD TAP..1
R 2
(-3450 600);
FORCEPROP 3 LASTPIN (-3400 600) SIG_NAME P5E_CPU0_P3_TX_BUF_DN<7>
J 0
(-3390 610);
DISPLAY 0.659574 (-3390 610);
PAINT MONO (-3390 610);
DISPLAY INVISIBLE (-3390 610);
FORCEPROP 1 LASTPIN (-3400 600) BN 7
J 2
(-3388 608);
DISPLAY 0.680851 (-3388 608);
PAINT GREEN (-3388 608);
FORCEPROP 2 LAST CDS_LIB standard
J 0
(-3450 600);
DISPLAY INVISIBLE (-3450 600);
FORCEPROP 1 LAST BODY_TYPE PLUMBING
J 2
(-3450 650);
DISPLAY 0.872340 (-3450 650);
PAINT GREEN (-3450 650);
DISPLAY INVISIBLE (-3450 650);
FORCEPROP 1 LAST HDL_TAP TRUE
J 2
(-3775 475);
DISPLAY 0.872340 (-3775 475);
DISPLAY INVISIBLE (-3775 475);
FORCEPROP 1 LAST PATH I5
J 2
(-3448 600);
DISPLAY 0.872340 (-3448 600);
PAINT GREEN (-3448 600);
DISPLAY INVISIBLE (-3448 600);
FORCEADD TAP..1
(-1725 2000);
FORCEPROP 3 LASTPIN (-1775 2000) SIG_NAME P5E_CPU0_P3_TX_BUF_C_DN<0>
J 0
(-1765 2010);
DISPLAY 0.659574 (-1765 2010);
PAINT MONO (-1765 2010);
DISPLAY INVISIBLE (-1765 2010);
FORCEPROP 1 LASTPIN (-1775 2000) BN 0
J 0
(-1787 2008);
DISPLAY 0.680851 (-1787 2008);
PAINT GREEN (-1787 2008);
FORCEPROP 2 LAST CDS_LIB standard
J 0
(-1725 2000);
DISPLAY INVISIBLE (-1725 2000);
FORCEPROP 1 LAST BODY_TYPE PLUMBING
J 0
(-1725 2050);
DISPLAY 0.872340 (-1725 2050);
PAINT GREEN (-1725 2050);
DISPLAY INVISIBLE (-1725 2050);
FORCEPROP 1 LAST HDL_TAP TRUE
J 0
(-1400 1875);
DISPLAY 0.872340 (-1400 1875);
DISPLAY INVISIBLE (-1400 1875);
FORCEPROP 1 LAST PATH I50
J 0
(-1727 2000);
DISPLAY 0.872340 (-1727 2000);
PAINT GREEN (-1727 2000);
DISPLAY INVISIBLE (-1727 2000);
FORCEADD PT5161LRS..10
(-7775 4525);
FORCEPROP 1 LAST LOCATION U6013
J 0
(-8125 6150);
DISPLAY 0.723404 (-8125 6150);
PAINT GREEN (-8125 6150);
FORCEPROP 0 LAST $SEC 10
J 0
(-8125 6300);
DISPLAY 0.680851 (-8125 6300);
PAINT MONO (-8125 6300);
DISPLAY INVISIBLE (-8125 6300);
FORCEPROP 0 LAST CDS_SEC 10
J 0
(-8125 6300);
DISPLAY 0.680851 (-8125 6300);
DISPLAY INVISIBLE (-8125 6300);
FORCEPROP 0 LASTPIN (-7325 5675) $PN P10
J 0
(-7315 5685);
DISPLAY 0.680851 (-7315 5685);
PAINT MONO (-7315 5685);
FORCEPROP 0 LASTPIN (-7325 5325) $PN AA10
J 0
(-7315 5335);
DISPLAY 0.680851 (-7315 5335);
PAINT MONO (-7315 5335);
FORCEPROP 0 LASTPIN (-7325 4975) $PN AH10
J 0
(-7315 4985);
DISPLAY 0.680851 (-7315 4985);
PAINT MONO (-7315 4985);
FORCEPROP 0 LASTPIN (-7325 4625) $PN AR10
J 0
(-7315 4635);
DISPLAY 0.680851 (-7315 4635);
PAINT MONO (-7315 4635);
FORCEPROP 0 LASTPIN (-7325 4275) $PN BB10
J 0
(-7315 4285);
DISPLAY 0.680851 (-7315 4285);
PAINT MONO (-7315 4285);
FORCEPROP 0 LASTPIN (-7325 3925) $PN BJ10
J 0
(-7315 3935);
DISPLAY 0.680851 (-7315 3935);
PAINT MONO (-7315 3935);
FORCEPROP 0 LASTPIN (-7325 3575) $PN BT10
J 0
(-7315 3585);
DISPLAY 0.680851 (-7315 3585);
PAINT MONO (-7315 3585);
FORCEPROP 0 LASTPIN (-7325 3225) $PN CC10
J 0
(-7315 3235);
DISPLAY 0.680851 (-7315 3235);
PAINT MONO (-7315 3235);
FORCEPROP 0 LASTPIN (-7325 5775) $PN M7
J 0
(-7315 5785);
DISPLAY 0.680851 (-7315 5785);
PAINT MONO (-7315 5785);
FORCEPROP 0 LASTPIN (-7325 5425) $PN W7
J 0
(-7315 5435);
DISPLAY 0.680851 (-7315 5435);
PAINT MONO (-7315 5435);
FORCEPROP 0 LASTPIN (-7325 5075) $PN AF7
J 0
(-7315 5085);
DISPLAY 0.680851 (-7315 5085);
PAINT MONO (-7315 5085);
FORCEPROP 0 LASTPIN (-7325 4725) $PN AN7
J 0
(-7315 4735);
DISPLAY 0.680851 (-7315 4735);
PAINT MONO (-7315 4735);
FORCEPROP 0 LASTPIN (-7325 4375) $PN AY7
J 0
(-7315 4385);
DISPLAY 0.680851 (-7315 4385);
PAINT MONO (-7315 4385);
FORCEPROP 0 LASTPIN (-7325 4025) $PN BG7
J 0
(-7315 4035);
DISPLAY 0.680851 (-7315 4035);
PAINT MONO (-7315 4035);
FORCEPROP 0 LASTPIN (-7325 3675) $PN BP7
J 0
(-7315 3685);
DISPLAY 0.680851 (-7315 3685);
PAINT MONO (-7315 3685);
FORCEPROP 0 LASTPIN (-7325 3325) $PN CA7
J 0
(-7315 3335);
DISPLAY 0.680851 (-7315 3335);
PAINT MONO (-7315 3335);
FORCEPROP 2 LAST VALUE PT5161LRS
J 0
(-8125 6200);
DISPLAY 0.680851 (-8125 6200);
FORCEPROP 2 LAST PART_TYPE SMLF
J 0
(-8125 6250);
DISPLAY 0.680851 (-8125 6250);
FORCEPROP 1 LAST MATERIAL IC
J 0
(-8125 6000);
DISPLAY 0.723404 (-8125 6000);
PAINT GREEN (-8125 6000);
FORCEPROP 2 LAST CDS_LIB pure_quanta
J 0
(-7775 4525);
DISPLAY INVISIBLE (-7775 4525);
FORCEPROP 1 LAST CDS_LMAN_SYM_OUTLINE -350,1450,300,-1400
J 0
(-7775 4525);
DISPLAY 0.468085 (-7775 4525);
PAINT GREEN (-7775 4525);
DISPLAY INVISIBLE (-7775 4525);
FORCEPROP 1 LAST NEEDS_NO_SIZE TRUE
J 0
(-7775 4525);
DISPLAY 0.723404 (-7775 4525);
PAINT GREEN (-7775 4525);
DISPLAY INVISIBLE (-7775 4525);
FORCEPROP 1 LAST PATH I51
J 0
(-7775 4525);
DISPLAY 0.723404 (-7775 4525);
PAINT GREEN (-7775 4525);
DISPLAY INVISIBLE (-7775 4525);
FORCEPROP 1 LAST PART_NUMBER AJ051610U03
J 0
(-8125 6075);
DISPLAY 0.723404 (-8125 6075);
PAINT GREEN (-8125 6075);
DISPLAY INVISIBLE (-8125 6075);
FORCEADD TAP..1
(-7050 3325);
FORCEPROP 3 LASTPIN (-7100 3325) SIG_NAME P5E_CPU0_P3_TX_BUF_DP<8>
J 0
(-7090 3335);
DISPLAY 0.659574 (-7090 3335);
PAINT MONO (-7090 3335);
DISPLAY INVISIBLE (-7090 3335);
FORCEPROP 1 LASTPIN (-7100 3325) BN 8
J 0
(-7112 3333);
DISPLAY 0.680851 (-7112 3333);
PAINT GREEN (-7112 3333);
FORCEPROP 2 LAST CDS_LIB standard
J 0
(-7050 3325);
DISPLAY INVISIBLE (-7050 3325);
FORCEPROP 1 LAST BODY_TYPE PLUMBING
J 0
(-7050 3375);
DISPLAY 0.872340 (-7050 3375);
PAINT GREEN (-7050 3375);
DISPLAY INVISIBLE (-7050 3375);
FORCEPROP 1 LAST HDL_TAP TRUE
J 0
(-6725 3200);
DISPLAY 0.872340 (-6725 3200);
DISPLAY INVISIBLE (-6725 3200);
FORCEPROP 1 LAST PATH I52
J 0
(-7052 3325);
DISPLAY 0.872340 (-7052 3325);
PAINT GREEN (-7052 3325);
DISPLAY INVISIBLE (-7052 3325);
FORCEADD TAP..1
(-6850 3225);
FORCEPROP 3 LASTPIN (-6900 3225) SIG_NAME P5E_CPU0_P3_TX_BUF_DN<8>
J 0
(-6890 3235);
DISPLAY 0.659574 (-6890 3235);
PAINT MONO (-6890 3235);
DISPLAY INVISIBLE (-6890 3235);
FORCEPROP 1 LASTPIN (-6900 3225) BN 8
J 0
(-6912 3233);
DISPLAY 0.680851 (-6912 3233);
PAINT GREEN (-6912 3233);
FORCEPROP 2 LAST CDS_LIB standard
J 0
(-6850 3225);
DISPLAY INVISIBLE (-6850 3225);
FORCEPROP 1 LAST BODY_TYPE PLUMBING
J 0
(-6850 3275);
DISPLAY 0.872340 (-6850 3275);
PAINT GREEN (-6850 3275);
DISPLAY INVISIBLE (-6850 3275);
FORCEPROP 1 LAST HDL_TAP TRUE
J 0
(-6525 3100);
DISPLAY 0.872340 (-6525 3100);
DISPLAY INVISIBLE (-6525 3100);
FORCEPROP 1 LAST PATH I53
J 0
(-6852 3225);
DISPLAY 0.872340 (-6852 3225);
PAINT GREEN (-6852 3225);
DISPLAY INVISIBLE (-6852 3225);
FORCEADD TAP..1
(-6850 3575);
FORCEPROP 3 LASTPIN (-6900 3575) SIG_NAME P5E_CPU0_P3_TX_BUF_DN<9>
J 0
(-6890 3585);
DISPLAY 0.659574 (-6890 3585);
PAINT MONO (-6890 3585);
DISPLAY INVISIBLE (-6890 3585);
FORCEPROP 1 LASTPIN (-6900 3575) BN 9
J 0
(-6912 3583);
DISPLAY 0.680851 (-6912 3583);
PAINT GREEN (-6912 3583);
FORCEPROP 2 LAST CDS_LIB standard
J 0
(-6850 3575);
DISPLAY INVISIBLE (-6850 3575);
FORCEPROP 1 LAST BODY_TYPE PLUMBING
J 0
(-6850 3625);
DISPLAY 0.872340 (-6850 3625);
PAINT GREEN (-6850 3625);
DISPLAY INVISIBLE (-6850 3625);
FORCEPROP 1 LAST HDL_TAP TRUE
J 0
(-6525 3450);
DISPLAY 0.872340 (-6525 3450);
DISPLAY INVISIBLE (-6525 3450);
FORCEPROP 1 LAST PATH I54
J 0
(-6852 3575);
DISPLAY 0.872340 (-6852 3575);
PAINT GREEN (-6852 3575);
DISPLAY INVISIBLE (-6852 3575);
FORCEADD TAP..1
(-7050 3675);
FORCEPROP 3 LASTPIN (-7100 3675) SIG_NAME P5E_CPU0_P3_TX_BUF_DP<9>
J 0
(-7090 3685);
DISPLAY 0.659574 (-7090 3685);
PAINT MONO (-7090 3685);
DISPLAY INVISIBLE (-7090 3685);
FORCEPROP 1 LASTPIN (-7100 3675) BN 9
J 0
(-7112 3683);
DISPLAY 0.680851 (-7112 3683);
PAINT GREEN (-7112 3683);
FORCEPROP 2 LAST CDS_LIB standard
J 0
(-7050 3675);
DISPLAY INVISIBLE (-7050 3675);
FORCEPROP 1 LAST BODY_TYPE PLUMBING
J 0
(-7050 3725);
DISPLAY 0.872340 (-7050 3725);
PAINT GREEN (-7050 3725);
DISPLAY INVISIBLE (-7050 3725);
FORCEPROP 1 LAST HDL_TAP TRUE
J 0
(-6725 3550);
DISPLAY 0.872340 (-6725 3550);
DISPLAY INVISIBLE (-6725 3550);
FORCEPROP 1 LAST PATH I55
J 0
(-7052 3675);
DISPLAY 0.872340 (-7052 3675);
PAINT GREEN (-7052 3675);
DISPLAY INVISIBLE (-7052 3675);
FORCEADD TAP..1
(-6850 3925);
FORCEPROP 3 LASTPIN (-6900 3925) SIG_NAME P5E_CPU0_P3_TX_BUF_DN<10>
J 0
(-6890 3935);
DISPLAY 0.659574 (-6890 3935);
PAINT MONO (-6890 3935);
DISPLAY INVISIBLE (-6890 3935);
FORCEPROP 1 LASTPIN (-6900 3925) BN 10
J 0
(-6912 3933);
DISPLAY 0.680851 (-6912 3933);
PAINT GREEN (-6912 3933);
FORCEPROP 2 LAST CDS_LIB standard
J 0
(-6850 3925);
DISPLAY INVISIBLE (-6850 3925);
FORCEPROP 1 LAST BODY_TYPE PLUMBING
J 0
(-6850 3975);
DISPLAY 0.872340 (-6850 3975);
PAINT GREEN (-6850 3975);
DISPLAY INVISIBLE (-6850 3975);
FORCEPROP 1 LAST HDL_TAP TRUE
J 0
(-6525 3800);
DISPLAY 0.872340 (-6525 3800);
DISPLAY INVISIBLE (-6525 3800);
FORCEPROP 1 LAST PATH I56
J 0
(-6852 3925);
DISPLAY 0.872340 (-6852 3925);
PAINT GREEN (-6852 3925);
DISPLAY INVISIBLE (-6852 3925);
FORCEADD TAP..1
(-7050 4025);
FORCEPROP 3 LASTPIN (-7100 4025) SIG_NAME P5E_CPU0_P3_TX_BUF_DP<10>
J 0
(-7090 4035);
DISPLAY 0.659574 (-7090 4035);
PAINT MONO (-7090 4035);
DISPLAY INVISIBLE (-7090 4035);
FORCEPROP 1 LASTPIN (-7100 4025) BN 10
J 0
(-7112 4033);
DISPLAY 0.680851 (-7112 4033);
PAINT GREEN (-7112 4033);
FORCEPROP 2 LAST CDS_LIB standard
J 0
(-7050 4025);
DISPLAY INVISIBLE (-7050 4025);
FORCEPROP 1 LAST BODY_TYPE PLUMBING
J 0
(-7050 4075);
DISPLAY 0.872340 (-7050 4075);
PAINT GREEN (-7050 4075);
DISPLAY INVISIBLE (-7050 4075);
FORCEPROP 1 LAST HDL_TAP TRUE
J 0
(-6725 3900);
DISPLAY 0.872340 (-6725 3900);
DISPLAY INVISIBLE (-6725 3900);
FORCEPROP 1 LAST PATH I57
J 0
(-7052 4025);
DISPLAY 0.872340 (-7052 4025);
PAINT GREEN (-7052 4025);
DISPLAY INVISIBLE (-7052 4025);
FORCEADD OFFPAGE..2
(-725 2025);
FORCEPROP 2 LAST $XR0 116 
J 0
(-536 2025);
DISPLAY 0.638298 (-536 2025);
PAINT MONO (-536 2025);
FORCEPROP 2 LAST CDS_LIB standard
J 0
(-725 2025);
DISPLAY INVISIBLE (-725 2025);
FORCEPROP 1 LAST OFFPAGE TRUE
J 0
(-400 1900);
DISPLAY 0.872340 (-400 1900);
DISPLAY INVISIBLE (-400 1900);
FORCEPROP 1 LAST COMMENT_BODY TRUE
J 0
(-770 1930);
DISPLAY 0.872340 (-770 1930);
PAINT GREEN (-770 1930);
DISPLAY INVISIBLE (-770 1930);
FORCEPROP 2 LAST PATH I58
J 0
(-525 2075);
DISPLAY 0.680851 (-525 2075);
DISPLAY INVISIBLE (-525 2075);
FORCEADD OFFPAGE..2
(-725 2075);
FORCEPROP 2 LAST $XR0 116 
J 0
(-536 2075);
DISPLAY 0.638298 (-536 2075);
PAINT MONO (-536 2075);
FORCEPROP 2 LAST CDS_LIB standard
J 0
(-725 2075);
DISPLAY INVISIBLE (-725 2075);
FORCEPROP 1 LAST OFFPAGE TRUE
J 0
(-400 1950);
DISPLAY 0.872340 (-400 1950);
DISPLAY INVISIBLE (-400 1950);
FORCEPROP 1 LAST COMMENT_BODY TRUE
J 0
(-770 1980);
DISPLAY 0.872340 (-770 1980);
PAINT GREEN (-770 1980);
DISPLAY INVISIBLE (-770 1980);
FORCEPROP 2 LAST PATH I59
J 0
(-525 2125);
DISPLAY 0.680851 (-525 2125);
DISPLAY INVISIBLE (-525 2125);
FORCEADD TAP..1
R 2
(-3200 650);
FORCEPROP 3 LASTPIN (-3150 650) SIG_NAME P5E_CPU0_P3_TX_BUF_DP<7>
J 0
(-3140 660);
DISPLAY 0.659574 (-3140 660);
PAINT MONO (-3140 660);
DISPLAY INVISIBLE (-3140 660);
FORCEPROP 1 LASTPIN (-3150 650) BN 7
J 2
(-3138 658);
DISPLAY 0.680851 (-3138 658);
PAINT GREEN (-3138 658);
FORCEPROP 2 LAST CDS_LIB standard
J 0
(-3200 650);
DISPLAY INVISIBLE (-3200 650);
FORCEPROP 1 LAST BODY_TYPE PLUMBING
J 2
(-3200 700);
DISPLAY 0.872340 (-3200 700);
PAINT GREEN (-3200 700);
DISPLAY INVISIBLE (-3200 700);
FORCEPROP 1 LAST HDL_TAP TRUE
J 2
(-3525 525);
DISPLAY 0.872340 (-3525 525);
DISPLAY INVISIBLE (-3525 525);
FORCEPROP 1 LAST PATH I6
J 2
(-3198 650);
DISPLAY 0.872340 (-3198 650);
PAINT GREEN (-3198 650);
DISPLAY INVISIBLE (-3198 650);
FORCEADD OFFPAGE..1
(-9000 2075);
FORCEPROP 2 LAST $XR0 309 
J 0
(-9252 2075);
DISPLAY 0.638298 (-9252 2075);
PAINT MONO (-9252 2075);
FORCEPROP 2 LAST CDS_LIB standard
J 0
(-9000 2075);
DISPLAY INVISIBLE (-9000 2075);
FORCEPROP 1 LAST OFFPAGE TRUE
J 0
(-8675 1950);
DISPLAY 0.872340 (-8675 1950);
DISPLAY INVISIBLE (-8675 1950);
FORCEPROP 1 LAST COMMENT_BODY TRUE
J 0
(-8875 1975);
DISPLAY 0.872340 (-8875 1975);
PAINT GREEN (-8875 1975);
DISPLAY INVISIBLE (-8875 1975);
FORCEPROP 2 LAST PATH I60
J 0
(-9250 2125);
DISPLAY 0.680851 (-9250 2125);
DISPLAY INVISIBLE (-9250 2125);
FORCEADD OFFPAGE..1
(-9000 2025);
FORCEPROP 2 LAST $XR0 309 
J 0
(-9252 2025);
DISPLAY 0.638298 (-9252 2025);
PAINT MONO (-9252 2025);
FORCEPROP 2 LAST CDS_LIB standard
J 0
(-9000 2025);
DISPLAY INVISIBLE (-9000 2025);
FORCEPROP 1 LAST OFFPAGE TRUE
J 0
(-8675 1900);
DISPLAY 0.872340 (-8675 1900);
DISPLAY INVISIBLE (-8675 1900);
FORCEPROP 1 LAST COMMENT_BODY TRUE
J 0
(-8875 1925);
DISPLAY 0.872340 (-8875 1925);
PAINT GREEN (-8875 1925);
DISPLAY INVISIBLE (-8875 1925);
FORCEPROP 2 LAST PATH I61
J 0
(-9250 2075);
DISPLAY 0.680851 (-9250 2075);
DISPLAY INVISIBLE (-9250 2075);
FORCEADD TAP..1
(-7050 4375);
FORCEPROP 3 LASTPIN (-7100 4375) SIG_NAME P5E_CPU0_P3_TX_BUF_DP<11>
J 0
(-7090 4385);
DISPLAY 0.659574 (-7090 4385);
PAINT MONO (-7090 4385);
DISPLAY INVISIBLE (-7090 4385);
FORCEPROP 1 LASTPIN (-7100 4375) BN 11
J 0
(-7112 4383);
DISPLAY 0.680851 (-7112 4383);
PAINT GREEN (-7112 4383);
FORCEPROP 2 LAST CDS_LIB standard
J 0
(-7050 4375);
DISPLAY INVISIBLE (-7050 4375);
FORCEPROP 1 LAST BODY_TYPE PLUMBING
J 0
(-7050 4425);
DISPLAY 0.872340 (-7050 4425);
PAINT GREEN (-7050 4425);
DISPLAY INVISIBLE (-7050 4425);
FORCEPROP 1 LAST HDL_TAP TRUE
J 0
(-6725 4250);
DISPLAY 0.872340 (-6725 4250);
DISPLAY INVISIBLE (-6725 4250);
FORCEPROP 1 LAST PATH I62
J 0
(-7052 4375);
DISPLAY 0.872340 (-7052 4375);
PAINT GREEN (-7052 4375);
DISPLAY INVISIBLE (-7052 4375);
FORCEADD TAP..1
(-6850 4275);
FORCEPROP 3 LASTPIN (-6900 4275) SIG_NAME P5E_CPU0_P3_TX_BUF_DN<11>
J 0
(-6890 4285);
DISPLAY 0.659574 (-6890 4285);
PAINT MONO (-6890 4285);
DISPLAY INVISIBLE (-6890 4285);
FORCEPROP 1 LASTPIN (-6900 4275) BN 11
J 0
(-6912 4283);
DISPLAY 0.680851 (-6912 4283);
PAINT GREEN (-6912 4283);
FORCEPROP 2 LAST CDS_LIB standard
J 0
(-6850 4275);
DISPLAY INVISIBLE (-6850 4275);
FORCEPROP 1 LAST BODY_TYPE PLUMBING
J 0
(-6850 4325);
DISPLAY 0.872340 (-6850 4325);
PAINT GREEN (-6850 4325);
DISPLAY INVISIBLE (-6850 4325);
FORCEPROP 1 LAST HDL_TAP TRUE
J 0
(-6525 4150);
DISPLAY 0.872340 (-6525 4150);
DISPLAY INVISIBLE (-6525 4150);
FORCEPROP 1 LAST PATH I63
J 0
(-6852 4275);
DISPLAY 0.872340 (-6852 4275);
PAINT GREEN (-6852 4275);
DISPLAY INVISIBLE (-6852 4275);
FORCEADD TAP..1
(-6850 4625);
FORCEPROP 3 LASTPIN (-6900 4625) SIG_NAME P5E_CPU0_P3_TX_BUF_DN<12>
J 0
(-6890 4635);
DISPLAY 0.659574 (-6890 4635);
PAINT MONO (-6890 4635);
DISPLAY INVISIBLE (-6890 4635);
FORCEPROP 1 LASTPIN (-6900 4625) BN 12
J 0
(-6912 4633);
DISPLAY 0.680851 (-6912 4633);
PAINT GREEN (-6912 4633);
FORCEPROP 2 LAST CDS_LIB standard
J 0
(-6850 4625);
DISPLAY INVISIBLE (-6850 4625);
FORCEPROP 1 LAST BODY_TYPE PLUMBING
J 0
(-6850 4675);
DISPLAY 0.872340 (-6850 4675);
PAINT GREEN (-6850 4675);
DISPLAY INVISIBLE (-6850 4675);
FORCEPROP 1 LAST HDL_TAP TRUE
J 0
(-6525 4500);
DISPLAY 0.872340 (-6525 4500);
DISPLAY INVISIBLE (-6525 4500);
FORCEPROP 1 LAST PATH I64
J 0
(-6852 4625);
DISPLAY 0.872340 (-6852 4625);
PAINT GREEN (-6852 4625);
DISPLAY INVISIBLE (-6852 4625);
FORCEADD TAP..1
(-7050 4725);
FORCEPROP 3 LASTPIN (-7100 4725) SIG_NAME P5E_CPU0_P3_TX_BUF_DP<12>
J 0
(-7090 4735);
DISPLAY 0.659574 (-7090 4735);
PAINT MONO (-7090 4735);
DISPLAY INVISIBLE (-7090 4735);
FORCEPROP 1 LASTPIN (-7100 4725) BN 12
J 0
(-7112 4733);
DISPLAY 0.680851 (-7112 4733);
PAINT GREEN (-7112 4733);
FORCEPROP 2 LAST CDS_LIB standard
J 0
(-7050 4725);
DISPLAY INVISIBLE (-7050 4725);
FORCEPROP 1 LAST BODY_TYPE PLUMBING
J 0
(-7050 4775);
DISPLAY 0.872340 (-7050 4775);
PAINT GREEN (-7050 4775);
DISPLAY INVISIBLE (-7050 4775);
FORCEPROP 1 LAST HDL_TAP TRUE
J 0
(-6725 4600);
DISPLAY 0.872340 (-6725 4600);
DISPLAY INVISIBLE (-6725 4600);
FORCEPROP 1 LAST PATH I65
J 0
(-7052 4725);
DISPLAY 0.872340 (-7052 4725);
PAINT GREEN (-7052 4725);
DISPLAY INVISIBLE (-7052 4725);
FORCEADD TAP..1
(-6850 4975);
FORCEPROP 3 LASTPIN (-6900 4975) SIG_NAME P5E_CPU0_P3_TX_BUF_DN<13>
J 0
(-6890 4985);
DISPLAY 0.659574 (-6890 4985);
PAINT MONO (-6890 4985);
DISPLAY INVISIBLE (-6890 4985);
FORCEPROP 1 LASTPIN (-6900 4975) BN 13
J 0
(-6912 4983);
DISPLAY 0.680851 (-6912 4983);
PAINT GREEN (-6912 4983);
FORCEPROP 2 LAST CDS_LIB standard
J 0
(-6850 4975);
DISPLAY INVISIBLE (-6850 4975);
FORCEPROP 1 LAST BODY_TYPE PLUMBING
J 0
(-6850 5025);
DISPLAY 0.872340 (-6850 5025);
PAINT GREEN (-6850 5025);
DISPLAY INVISIBLE (-6850 5025);
FORCEPROP 1 LAST HDL_TAP TRUE
J 0
(-6525 4850);
DISPLAY 0.872340 (-6525 4850);
DISPLAY INVISIBLE (-6525 4850);
FORCEPROP 1 LAST PATH I66
J 0
(-6852 4975);
DISPLAY 0.872340 (-6852 4975);
PAINT GREEN (-6852 4975);
DISPLAY INVISIBLE (-6852 4975);
FORCEADD TAP..1
(-7050 5075);
FORCEPROP 3 LASTPIN (-7100 5075) SIG_NAME P5E_CPU0_P3_TX_BUF_DP<13>
J 0
(-7090 5085);
DISPLAY 0.659574 (-7090 5085);
PAINT MONO (-7090 5085);
DISPLAY INVISIBLE (-7090 5085);
FORCEPROP 1 LASTPIN (-7100 5075) BN 13
J 0
(-7112 5083);
DISPLAY 0.680851 (-7112 5083);
PAINT GREEN (-7112 5083);
FORCEPROP 2 LAST CDS_LIB standard
J 0
(-7050 5075);
DISPLAY INVISIBLE (-7050 5075);
FORCEPROP 1 LAST BODY_TYPE PLUMBING
J 0
(-7050 5125);
DISPLAY 0.872340 (-7050 5125);
PAINT GREEN (-7050 5125);
DISPLAY INVISIBLE (-7050 5125);
FORCEPROP 1 LAST HDL_TAP TRUE
J 0
(-6725 4950);
DISPLAY 0.872340 (-6725 4950);
DISPLAY INVISIBLE (-6725 4950);
FORCEPROP 1 LAST PATH I67
J 0
(-7052 5075);
DISPLAY 0.872340 (-7052 5075);
PAINT GREEN (-7052 5075);
DISPLAY INVISIBLE (-7052 5075);
FORCEADD TAP..1
(-7050 5425);
FORCEPROP 3 LASTPIN (-7100 5425) SIG_NAME P5E_CPU0_P3_TX_BUF_DP<14>
J 0
(-7090 5435);
DISPLAY 0.659574 (-7090 5435);
PAINT MONO (-7090 5435);
DISPLAY INVISIBLE (-7090 5435);
FORCEPROP 1 LASTPIN (-7100 5425) BN 14
J 0
(-7112 5433);
DISPLAY 0.680851 (-7112 5433);
PAINT GREEN (-7112 5433);
FORCEPROP 2 LAST CDS_LIB standard
J 0
(-7050 5425);
DISPLAY INVISIBLE (-7050 5425);
FORCEPROP 1 LAST BODY_TYPE PLUMBING
J 0
(-7050 5475);
DISPLAY 0.872340 (-7050 5475);
PAINT GREEN (-7050 5475);
DISPLAY INVISIBLE (-7050 5475);
FORCEPROP 1 LAST HDL_TAP TRUE
J 0
(-6725 5300);
DISPLAY 0.872340 (-6725 5300);
DISPLAY INVISIBLE (-6725 5300);
FORCEPROP 1 LAST PATH I68
J 0
(-7052 5425);
DISPLAY 0.872340 (-7052 5425);
PAINT GREEN (-7052 5425);
DISPLAY INVISIBLE (-7052 5425);
FORCEADD TAP..1
(-6850 5325);
FORCEPROP 3 LASTPIN (-6900 5325) SIG_NAME P5E_CPU0_P3_TX_BUF_DN<14>
J 0
(-6890 5335);
DISPLAY 0.659574 (-6890 5335);
PAINT MONO (-6890 5335);
DISPLAY INVISIBLE (-6890 5335);
FORCEPROP 1 LASTPIN (-6900 5325) BN 14
J 0
(-6912 5333);
DISPLAY 0.680851 (-6912 5333);
PAINT GREEN (-6912 5333);
FORCEPROP 2 LAST CDS_LIB standard
J 0
(-6850 5325);
DISPLAY INVISIBLE (-6850 5325);
FORCEPROP 1 LAST BODY_TYPE PLUMBING
J 0
(-6850 5375);
DISPLAY 0.872340 (-6850 5375);
PAINT GREEN (-6850 5375);
DISPLAY INVISIBLE (-6850 5375);
FORCEPROP 1 LAST HDL_TAP TRUE
J 0
(-6525 5200);
DISPLAY 0.872340 (-6525 5200);
DISPLAY INVISIBLE (-6525 5200);
FORCEPROP 1 LAST PATH I69
J 0
(-6852 5325);
DISPLAY 0.872340 (-6852 5325);
PAINT GREEN (-6852 5325);
DISPLAY INVISIBLE (-6852 5325);
FORCEADD TAP..1
R 2
(-3200 850);
FORCEPROP 3 LASTPIN (-3150 850) SIG_NAME P5E_CPU0_P3_TX_BUF_DP<6>
J 0
(-3140 860);
DISPLAY 0.659574 (-3140 860);
PAINT MONO (-3140 860);
DISPLAY INVISIBLE (-3140 860);
FORCEPROP 1 LASTPIN (-3150 850) BN 6
J 2
(-3138 858);
DISPLAY 0.680851 (-3138 858);
PAINT GREEN (-3138 858);
FORCEPROP 2 LAST CDS_LIB standard
J 0
(-3200 850);
DISPLAY INVISIBLE (-3200 850);
FORCEPROP 1 LAST BODY_TYPE PLUMBING
J 2
(-3200 900);
DISPLAY 0.872340 (-3200 900);
PAINT GREEN (-3200 900);
DISPLAY INVISIBLE (-3200 900);
FORCEPROP 1 LAST HDL_TAP TRUE
J 2
(-3525 725);
DISPLAY 0.872340 (-3525 725);
DISPLAY INVISIBLE (-3525 725);
FORCEPROP 1 LAST PATH I7
J 2
(-3198 850);
DISPLAY 0.872340 (-3198 850);
PAINT GREEN (-3198 850);
DISPLAY INVISIBLE (-3198 850);
FORCEADD TAP..1
(-7050 5775);
FORCEPROP 3 LASTPIN (-7100 5775) SIG_NAME P5E_CPU0_P3_TX_BUF_DP<15>
J 0
(-7090 5785);
DISPLAY 0.659574 (-7090 5785);
PAINT MONO (-7090 5785);
DISPLAY INVISIBLE (-7090 5785);
FORCEPROP 1 LASTPIN (-7100 5775) BN 15
J 0
(-7112 5783);
DISPLAY 0.680851 (-7112 5783);
PAINT GREEN (-7112 5783);
FORCEPROP 2 LAST CDS_LIB standard
J 0
(-7050 5775);
DISPLAY INVISIBLE (-7050 5775);
FORCEPROP 1 LAST BODY_TYPE PLUMBING
J 0
(-7050 5825);
DISPLAY 0.872340 (-7050 5825);
PAINT GREEN (-7050 5825);
DISPLAY INVISIBLE (-7050 5825);
FORCEPROP 1 LAST HDL_TAP TRUE
J 0
(-6725 5650);
DISPLAY 0.872340 (-6725 5650);
DISPLAY INVISIBLE (-6725 5650);
FORCEPROP 1 LAST PATH I70
J 0
(-7052 5775);
DISPLAY 0.872340 (-7052 5775);
PAINT GREEN (-7052 5775);
DISPLAY INVISIBLE (-7052 5775);
FORCEADD TAP..1
(-6850 5675);
FORCEPROP 3 LASTPIN (-6900 5675) SIG_NAME P5E_CPU0_P3_TX_BUF_DN<15>
J 0
(-6890 5685);
DISPLAY 0.659574 (-6890 5685);
PAINT MONO (-6890 5685);
DISPLAY INVISIBLE (-6890 5685);
FORCEPROP 1 LASTPIN (-6900 5675) BN 15
J 0
(-6912 5683);
DISPLAY 0.680851 (-6912 5683);
PAINT GREEN (-6912 5683);
FORCEPROP 2 LAST CDS_LIB standard
J 0
(-6850 5675);
DISPLAY INVISIBLE (-6850 5675);
FORCEPROP 1 LAST BODY_TYPE PLUMBING
J 0
(-6850 5725);
DISPLAY 0.872340 (-6850 5725);
PAINT GREEN (-6850 5725);
DISPLAY INVISIBLE (-6850 5725);
FORCEPROP 1 LAST HDL_TAP TRUE
J 0
(-6525 5550);
DISPLAY 0.872340 (-6525 5550);
DISPLAY INVISIBLE (-6525 5550);
FORCEPROP 1 LAST PATH I71
J 0
(-6852 5675);
DISPLAY 0.872340 (-6852 5675);
PAINT GREEN (-6852 5675);
DISPLAY INVISIBLE (-6852 5675);
FORCEADD OFFPAGE..5
R 2
(-5875 5700);
FORCEPROP 2 LAST $XR0 309 
J 0
(-5686 5700);
DISPLAY 0.638298 (-5686 5700);
PAINT MONO (-5686 5700);
FORCEPROP 2 LAST CDS_LIB standard
J 0
(-5875 5700);
DISPLAY INVISIBLE (-5875 5700);
FORCEPROP 1 LAST OFFPAGE TRUE
J 2
(-6200 5575);
DISPLAY 0.872340 (-6200 5575);
PAINT GREEN (-6200 5575);
DISPLAY INVISIBLE (-6200 5575);
FORCEPROP 1 LAST COMMENT_BODY TRUE
J 2
(-5975 5625);
DISPLAY 0.872340 (-5975 5625);
PAINT GREEN (-5975 5625);
DISPLAY INVISIBLE (-5975 5625);
FORCEPROP 2 LAST PATH I72
J 0
(-5700 5775);
DISPLAY 0.680851 (-5700 5775);
DISPLAY INVISIBLE (-5700 5775);
FORCEADD OFFPAGE..5
R 2
(-5850 5800);
FORCEPROP 2 LAST $XR0 309 
J 0
(-5661 5800);
DISPLAY 0.638298 (-5661 5800);
PAINT MONO (-5661 5800);
FORCEPROP 2 LAST CDS_LIB standard
J 0
(-5850 5800);
DISPLAY INVISIBLE (-5850 5800);
FORCEPROP 1 LAST OFFPAGE TRUE
J 2
(-6175 5675);
DISPLAY 0.872340 (-6175 5675);
PAINT GREEN (-6175 5675);
DISPLAY INVISIBLE (-6175 5675);
FORCEPROP 1 LAST COMMENT_BODY TRUE
J 2
(-5950 5725);
DISPLAY 0.872340 (-5950 5725);
PAINT GREEN (-5950 5725);
DISPLAY INVISIBLE (-5950 5725);
FORCEPROP 2 LAST PATH I73
J 0
(-5675 5875);
DISPLAY 0.680851 (-5675 5875);
DISPLAY INVISIBLE (-5675 5875);
FORCEADD TAP..1
R 2
(-8050 600);
FORCEPROP 3 LASTPIN (-8000 600) SIG_NAME P5E_CPU0_P3_TX_BUF_DN<15>
J 0
(-7990 610);
DISPLAY 0.659574 (-7990 610);
PAINT MONO (-7990 610);
DISPLAY INVISIBLE (-7990 610);
FORCEPROP 1 LASTPIN (-8000 600) BN 15
J 2
(-7988 608);
DISPLAY 0.680851 (-7988 608);
PAINT GREEN (-7988 608);
FORCEPROP 2 LAST CDS_LIB standard
J 0
(-8050 600);
DISPLAY INVISIBLE (-8050 600);
FORCEPROP 1 LAST BODY_TYPE PLUMBING
J 2
(-8050 650);
DISPLAY 0.872340 (-8050 650);
PAINT GREEN (-8050 650);
DISPLAY INVISIBLE (-8050 650);
FORCEPROP 1 LAST HDL_TAP TRUE
J 2
(-8375 475);
DISPLAY 0.872340 (-8375 475);
DISPLAY INVISIBLE (-8375 475);
FORCEPROP 1 LAST PATH I74
J 2
(-8048 600);
DISPLAY 0.872340 (-8048 600);
PAINT GREEN (-8048 600);
DISPLAY INVISIBLE (-8048 600);
FORCEADD TAP..1
R 2
(-8050 800);
FORCEPROP 3 LASTPIN (-8000 800) SIG_NAME P5E_CPU0_P3_TX_BUF_DN<14>
J 0
(-7990 810);
DISPLAY 0.659574 (-7990 810);
PAINT MONO (-7990 810);
DISPLAY INVISIBLE (-7990 810);
FORCEPROP 1 LASTPIN (-8000 800) BN 14
J 2
(-7988 808);
DISPLAY 0.680851 (-7988 808);
PAINT GREEN (-7988 808);
FORCEPROP 2 LAST CDS_LIB standard
J 0
(-8050 800);
DISPLAY INVISIBLE (-8050 800);
FORCEPROP 1 LAST BODY_TYPE PLUMBING
J 2
(-8050 850);
DISPLAY 0.872340 (-8050 850);
PAINT GREEN (-8050 850);
DISPLAY INVISIBLE (-8050 850);
FORCEPROP 1 LAST HDL_TAP TRUE
J 2
(-8375 675);
DISPLAY 0.872340 (-8375 675);
DISPLAY INVISIBLE (-8375 675);
FORCEPROP 1 LAST PATH I75
J 2
(-8048 800);
DISPLAY 0.872340 (-8048 800);
PAINT GREEN (-8048 800);
DISPLAY INVISIBLE (-8048 800);
FORCEADD TAP..1
R 2
(-8050 1000);
FORCEPROP 3 LASTPIN (-8000 1000) SIG_NAME P5E_CPU0_P3_TX_BUF_DN<13>
J 0
(-7990 1010);
DISPLAY 0.659574 (-7990 1010);
PAINT MONO (-7990 1010);
DISPLAY INVISIBLE (-7990 1010);
FORCEPROP 1 LASTPIN (-8000 1000) BN 13
J 2
(-7988 1008);
DISPLAY 0.680851 (-7988 1008);
PAINT GREEN (-7988 1008);
FORCEPROP 2 LAST CDS_LIB standard
J 0
(-8050 1000);
DISPLAY INVISIBLE (-8050 1000);
FORCEPROP 1 LAST BODY_TYPE PLUMBING
J 2
(-8050 1050);
DISPLAY 0.872340 (-8050 1050);
PAINT GREEN (-8050 1050);
DISPLAY INVISIBLE (-8050 1050);
FORCEPROP 1 LAST HDL_TAP TRUE
J 2
(-8375 875);
DISPLAY 0.872340 (-8375 875);
DISPLAY INVISIBLE (-8375 875);
FORCEPROP 1 LAST PATH I76
J 2
(-8048 1000);
DISPLAY 0.872340 (-8048 1000);
PAINT GREEN (-8048 1000);
DISPLAY INVISIBLE (-8048 1000);
FORCEADD TAP..1
R 2
(-7800 650);
FORCEPROP 3 LASTPIN (-7750 650) SIG_NAME P5E_CPU0_P3_TX_BUF_DP<15>
J 0
(-7740 660);
DISPLAY 0.659574 (-7740 660);
PAINT MONO (-7740 660);
DISPLAY INVISIBLE (-7740 660);
FORCEPROP 1 LASTPIN (-7750 650) BN 15
J 2
(-7738 658);
DISPLAY 0.680851 (-7738 658);
PAINT GREEN (-7738 658);
FORCEPROP 2 LAST CDS_LIB standard
J 0
(-7800 650);
DISPLAY INVISIBLE (-7800 650);
FORCEPROP 1 LAST BODY_TYPE PLUMBING
J 2
(-7800 700);
DISPLAY 0.872340 (-7800 700);
PAINT GREEN (-7800 700);
DISPLAY INVISIBLE (-7800 700);
FORCEPROP 1 LAST HDL_TAP TRUE
J 2
(-8125 525);
DISPLAY 0.872340 (-8125 525);
DISPLAY INVISIBLE (-8125 525);
FORCEPROP 1 LAST PATH I77
J 2
(-7798 650);
DISPLAY 0.872340 (-7798 650);
PAINT GREEN (-7798 650);
DISPLAY INVISIBLE (-7798 650);
FORCEADD TAP..1
R 2
(-7800 850);
FORCEPROP 3 LASTPIN (-7750 850) SIG_NAME P5E_CPU0_P3_TX_BUF_DP<14>
J 0
(-7740 860);
DISPLAY 0.659574 (-7740 860);
PAINT MONO (-7740 860);
DISPLAY INVISIBLE (-7740 860);
FORCEPROP 1 LASTPIN (-7750 850) BN 14
J 2
(-7738 858);
DISPLAY 0.680851 (-7738 858);
PAINT GREEN (-7738 858);
FORCEPROP 2 LAST CDS_LIB standard
J 0
(-7800 850);
DISPLAY INVISIBLE (-7800 850);
FORCEPROP 1 LAST BODY_TYPE PLUMBING
J 2
(-7800 900);
DISPLAY 0.872340 (-7800 900);
PAINT GREEN (-7800 900);
DISPLAY INVISIBLE (-7800 900);
FORCEPROP 1 LAST HDL_TAP TRUE
J 2
(-8125 725);
DISPLAY 0.872340 (-8125 725);
DISPLAY INVISIBLE (-8125 725);
FORCEPROP 1 LAST PATH I78
J 2
(-7798 850);
DISPLAY 0.872340 (-7798 850);
PAINT GREEN (-7798 850);
DISPLAY INVISIBLE (-7798 850);
FORCEADD TAP..1
R 2
(-7800 1050);
FORCEPROP 3 LASTPIN (-7750 1050) SIG_NAME P5E_CPU0_P3_TX_BUF_DP<13>
J 0
(-7740 1060);
DISPLAY 0.659574 (-7740 1060);
PAINT MONO (-7740 1060);
DISPLAY INVISIBLE (-7740 1060);
FORCEPROP 1 LASTPIN (-7750 1050) BN 13
J 2
(-7738 1058);
DISPLAY 0.680851 (-7738 1058);
PAINT GREEN (-7738 1058);
FORCEPROP 2 LAST CDS_LIB standard
J 0
(-7800 1050);
DISPLAY INVISIBLE (-7800 1050);
FORCEPROP 1 LAST BODY_TYPE PLUMBING
J 2
(-7800 1100);
DISPLAY 0.872340 (-7800 1100);
PAINT GREEN (-7800 1100);
DISPLAY INVISIBLE (-7800 1100);
FORCEPROP 1 LAST HDL_TAP TRUE
J 2
(-8125 925);
DISPLAY 0.872340 (-8125 925);
DISPLAY INVISIBLE (-8125 925);
FORCEPROP 1 LAST PATH I79
J 2
(-7798 1050);
DISPLAY 0.872340 (-7798 1050);
PAINT GREEN (-7798 1050);
DISPLAY INVISIBLE (-7798 1050);
FORCEADD TAP..1
R 2
(-3200 1050);
FORCEPROP 3 LASTPIN (-3150 1050) SIG_NAME P5E_CPU0_P3_TX_BUF_DP<5>
J 0
(-3140 1060);
DISPLAY 0.659574 (-3140 1060);
PAINT MONO (-3140 1060);
DISPLAY INVISIBLE (-3140 1060);
FORCEPROP 1 LASTPIN (-3150 1050) BN 5
J 2
(-3138 1058);
DISPLAY 0.680851 (-3138 1058);
PAINT GREEN (-3138 1058);
FORCEPROP 2 LAST CDS_LIB standard
J 0
(-3200 1050);
DISPLAY INVISIBLE (-3200 1050);
FORCEPROP 1 LAST BODY_TYPE PLUMBING
J 2
(-3200 1100);
DISPLAY 0.872340 (-3200 1100);
PAINT GREEN (-3200 1100);
DISPLAY INVISIBLE (-3200 1100);
FORCEPROP 1 LAST HDL_TAP TRUE
J 2
(-3525 925);
DISPLAY 0.872340 (-3525 925);
DISPLAY INVISIBLE (-3525 925);
FORCEPROP 1 LAST PATH I8
J 2
(-3198 1050);
DISPLAY 0.872340 (-3198 1050);
PAINT GREEN (-3198 1050);
DISPLAY INVISIBLE (-3198 1050);
FORCEADD TAP..1
R 2
(-8050 1200);
FORCEPROP 3 LASTPIN (-8000 1200) SIG_NAME P5E_CPU0_P3_TX_BUF_DN<12>
J 0
(-7990 1210);
DISPLAY 0.659574 (-7990 1210);
PAINT MONO (-7990 1210);
DISPLAY INVISIBLE (-7990 1210);
FORCEPROP 1 LASTPIN (-8000 1200) BN 12
J 2
(-7988 1208);
DISPLAY 0.680851 (-7988 1208);
PAINT GREEN (-7988 1208);
FORCEPROP 2 LAST CDS_LIB standard
J 0
(-8050 1200);
DISPLAY INVISIBLE (-8050 1200);
FORCEPROP 1 LAST BODY_TYPE PLUMBING
J 2
(-8050 1250);
DISPLAY 0.872340 (-8050 1250);
PAINT GREEN (-8050 1250);
DISPLAY INVISIBLE (-8050 1250);
FORCEPROP 1 LAST HDL_TAP TRUE
J 2
(-8375 1075);
DISPLAY 0.872340 (-8375 1075);
DISPLAY INVISIBLE (-8375 1075);
FORCEPROP 1 LAST PATH I80
J 2
(-8048 1200);
DISPLAY 0.872340 (-8048 1200);
PAINT GREEN (-8048 1200);
DISPLAY INVISIBLE (-8048 1200);
FORCEADD TAP..1
R 2
(-8050 1400);
FORCEPROP 3 LASTPIN (-8000 1400) SIG_NAME P5E_CPU0_P3_TX_BUF_DN<11>
J 0
(-7990 1410);
DISPLAY 0.659574 (-7990 1410);
PAINT MONO (-7990 1410);
DISPLAY INVISIBLE (-7990 1410);
FORCEPROP 1 LASTPIN (-8000 1400) BN 11
J 2
(-7988 1408);
DISPLAY 0.680851 (-7988 1408);
PAINT GREEN (-7988 1408);
FORCEPROP 2 LAST CDS_LIB standard
J 0
(-8050 1400);
DISPLAY INVISIBLE (-8050 1400);
FORCEPROP 1 LAST BODY_TYPE PLUMBING
J 2
(-8050 1450);
DISPLAY 0.872340 (-8050 1450);
PAINT GREEN (-8050 1450);
DISPLAY INVISIBLE (-8050 1450);
FORCEPROP 1 LAST HDL_TAP TRUE
J 2
(-8375 1275);
DISPLAY 0.872340 (-8375 1275);
DISPLAY INVISIBLE (-8375 1275);
FORCEPROP 1 LAST PATH I81
J 2
(-8048 1400);
DISPLAY 0.872340 (-8048 1400);
PAINT GREEN (-8048 1400);
DISPLAY INVISIBLE (-8048 1400);
FORCEADD TAP..1
R 2
(-8050 1600);
FORCEPROP 3 LASTPIN (-8000 1600) SIG_NAME P5E_CPU0_P3_TX_BUF_DN<10>
J 0
(-7990 1610);
DISPLAY 0.659574 (-7990 1610);
PAINT MONO (-7990 1610);
DISPLAY INVISIBLE (-7990 1610);
FORCEPROP 1 LASTPIN (-8000 1600) BN 10
J 2
(-7988 1608);
DISPLAY 0.680851 (-7988 1608);
PAINT GREEN (-7988 1608);
FORCEPROP 2 LAST CDS_LIB standard
J 0
(-8050 1600);
DISPLAY INVISIBLE (-8050 1600);
FORCEPROP 1 LAST BODY_TYPE PLUMBING
J 2
(-8050 1650);
DISPLAY 0.872340 (-8050 1650);
PAINT GREEN (-8050 1650);
DISPLAY INVISIBLE (-8050 1650);
FORCEPROP 1 LAST HDL_TAP TRUE
J 2
(-8375 1475);
DISPLAY 0.872340 (-8375 1475);
DISPLAY INVISIBLE (-8375 1475);
FORCEPROP 1 LAST PATH I82
J 2
(-8048 1600);
DISPLAY 0.872340 (-8048 1600);
PAINT GREEN (-8048 1600);
DISPLAY INVISIBLE (-8048 1600);
FORCEADD TAP..1
R 2
(-7800 1250);
FORCEPROP 3 LASTPIN (-7750 1250) SIG_NAME P5E_CPU0_P3_TX_BUF_DP<12>
J 0
(-7740 1260);
DISPLAY 0.659574 (-7740 1260);
PAINT MONO (-7740 1260);
DISPLAY INVISIBLE (-7740 1260);
FORCEPROP 1 LASTPIN (-7750 1250) BN 12
J 2
(-7738 1258);
DISPLAY 0.680851 (-7738 1258);
PAINT GREEN (-7738 1258);
FORCEPROP 2 LAST CDS_LIB standard
J 0
(-7800 1250);
DISPLAY INVISIBLE (-7800 1250);
FORCEPROP 1 LAST BODY_TYPE PLUMBING
J 2
(-7800 1300);
DISPLAY 0.872340 (-7800 1300);
PAINT GREEN (-7800 1300);
DISPLAY INVISIBLE (-7800 1300);
FORCEPROP 1 LAST HDL_TAP TRUE
J 2
(-8125 1125);
DISPLAY 0.872340 (-8125 1125);
DISPLAY INVISIBLE (-8125 1125);
FORCEPROP 1 LAST PATH I83
J 2
(-7798 1250);
DISPLAY 0.872340 (-7798 1250);
PAINT GREEN (-7798 1250);
DISPLAY INVISIBLE (-7798 1250);
FORCEADD TAP..1
R 2
(-7800 1450);
FORCEPROP 3 LASTPIN (-7750 1450) SIG_NAME P5E_CPU0_P3_TX_BUF_DP<11>
J 0
(-7740 1460);
DISPLAY 0.659574 (-7740 1460);
PAINT MONO (-7740 1460);
DISPLAY INVISIBLE (-7740 1460);
FORCEPROP 1 LASTPIN (-7750 1450) BN 11
J 2
(-7738 1458);
DISPLAY 0.680851 (-7738 1458);
PAINT GREEN (-7738 1458);
FORCEPROP 2 LAST CDS_LIB standard
J 0
(-7800 1450);
DISPLAY INVISIBLE (-7800 1450);
FORCEPROP 1 LAST BODY_TYPE PLUMBING
J 2
(-7800 1500);
DISPLAY 0.872340 (-7800 1500);
PAINT GREEN (-7800 1500);
DISPLAY INVISIBLE (-7800 1500);
FORCEPROP 1 LAST HDL_TAP TRUE
J 2
(-8125 1325);
DISPLAY 0.872340 (-8125 1325);
DISPLAY INVISIBLE (-8125 1325);
FORCEPROP 1 LAST PATH I84
J 2
(-7798 1450);
DISPLAY 0.872340 (-7798 1450);
PAINT GREEN (-7798 1450);
DISPLAY INVISIBLE (-7798 1450);
FORCEADD TAP..1
R 2
(-8050 1800);
FORCEPROP 3 LASTPIN (-8000 1800) SIG_NAME P5E_CPU0_P3_TX_BUF_DN<9>
J 0
(-7990 1810);
DISPLAY 0.659574 (-7990 1810);
PAINT MONO (-7990 1810);
DISPLAY INVISIBLE (-7990 1810);
FORCEPROP 1 LASTPIN (-8000 1800) BN 9
J 2
(-7988 1808);
DISPLAY 0.680851 (-7988 1808);
PAINT GREEN (-7988 1808);
FORCEPROP 2 LAST CDS_LIB standard
J 0
(-8050 1800);
DISPLAY INVISIBLE (-8050 1800);
FORCEPROP 1 LAST BODY_TYPE PLUMBING
J 2
(-8050 1850);
DISPLAY 0.872340 (-8050 1850);
PAINT GREEN (-8050 1850);
DISPLAY INVISIBLE (-8050 1850);
FORCEPROP 1 LAST HDL_TAP TRUE
J 2
(-8375 1675);
DISPLAY 0.872340 (-8375 1675);
DISPLAY INVISIBLE (-8375 1675);
FORCEPROP 1 LAST PATH I85
J 2
(-8048 1800);
DISPLAY 0.872340 (-8048 1800);
PAINT GREEN (-8048 1800);
DISPLAY INVISIBLE (-8048 1800);
FORCEADD TAP..1
R 2
(-8050 2000);
FORCEPROP 3 LASTPIN (-8000 2000) SIG_NAME P5E_CPU0_P3_TX_BUF_DN<8>
J 0
(-7990 2010);
DISPLAY 0.659574 (-7990 2010);
PAINT MONO (-7990 2010);
DISPLAY INVISIBLE (-7990 2010);
FORCEPROP 1 LASTPIN (-8000 2000) BN 8
J 2
(-7988 2008);
DISPLAY 0.680851 (-7988 2008);
PAINT GREEN (-7988 2008);
FORCEPROP 2 LAST CDS_LIB standard
J 0
(-8050 2000);
DISPLAY INVISIBLE (-8050 2000);
FORCEPROP 1 LAST BODY_TYPE PLUMBING
J 2
(-8050 2050);
DISPLAY 0.872340 (-8050 2050);
PAINT GREEN (-8050 2050);
DISPLAY INVISIBLE (-8050 2050);
FORCEPROP 1 LAST HDL_TAP TRUE
J 2
(-8375 1875);
DISPLAY 0.872340 (-8375 1875);
DISPLAY INVISIBLE (-8375 1875);
FORCEPROP 1 LAST PATH I86
J 2
(-8048 2000);
DISPLAY 0.872340 (-8048 2000);
PAINT GREEN (-8048 2000);
DISPLAY INVISIBLE (-8048 2000);
FORCEADD TAP..1
R 2
(-7800 1650);
FORCEPROP 3 LASTPIN (-7750 1650) SIG_NAME P5E_CPU0_P3_TX_BUF_DP<10>
J 0
(-7740 1660);
DISPLAY 0.659574 (-7740 1660);
PAINT MONO (-7740 1660);
DISPLAY INVISIBLE (-7740 1660);
FORCEPROP 1 LASTPIN (-7750 1650) BN 10
J 2
(-7738 1658);
DISPLAY 0.680851 (-7738 1658);
PAINT GREEN (-7738 1658);
FORCEPROP 2 LAST CDS_LIB standard
J 0
(-7800 1650);
DISPLAY INVISIBLE (-7800 1650);
FORCEPROP 1 LAST BODY_TYPE PLUMBING
J 2
(-7800 1700);
DISPLAY 0.872340 (-7800 1700);
PAINT GREEN (-7800 1700);
DISPLAY INVISIBLE (-7800 1700);
FORCEPROP 1 LAST HDL_TAP TRUE
J 2
(-8125 1525);
DISPLAY 0.872340 (-8125 1525);
DISPLAY INVISIBLE (-8125 1525);
FORCEPROP 1 LAST PATH I87
J 2
(-7798 1650);
DISPLAY 0.872340 (-7798 1650);
PAINT GREEN (-7798 1650);
DISPLAY INVISIBLE (-7798 1650);
FORCEADD TAP..1
R 2
(-7800 1850);
FORCEPROP 3 LASTPIN (-7750 1850) SIG_NAME P5E_CPU0_P3_TX_BUF_DP<9>
J 0
(-7740 1860);
DISPLAY 0.659574 (-7740 1860);
PAINT MONO (-7740 1860);
DISPLAY INVISIBLE (-7740 1860);
FORCEPROP 1 LASTPIN (-7750 1850) BN 9
J 2
(-7738 1858);
DISPLAY 0.680851 (-7738 1858);
PAINT GREEN (-7738 1858);
FORCEPROP 2 LAST CDS_LIB standard
J 0
(-7800 1850);
DISPLAY INVISIBLE (-7800 1850);
FORCEPROP 1 LAST BODY_TYPE PLUMBING
J 2
(-7800 1900);
DISPLAY 0.872340 (-7800 1900);
PAINT GREEN (-7800 1900);
DISPLAY INVISIBLE (-7800 1900);
FORCEPROP 1 LAST HDL_TAP TRUE
J 2
(-8125 1725);
DISPLAY 0.872340 (-8125 1725);
DISPLAY INVISIBLE (-8125 1725);
FORCEPROP 1 LAST PATH I88
J 2
(-7798 1850);
DISPLAY 0.872340 (-7798 1850);
PAINT GREEN (-7798 1850);
DISPLAY INVISIBLE (-7798 1850);
FORCEADD TAP..1
R 2
(-7800 2050);
FORCEPROP 3 LASTPIN (-7750 2050) SIG_NAME P5E_CPU0_P3_TX_BUF_DP<8>
J 0
(-7740 2060);
DISPLAY 0.659574 (-7740 2060);
PAINT MONO (-7740 2060);
DISPLAY INVISIBLE (-7740 2060);
FORCEPROP 1 LASTPIN (-7750 2050) BN 8
J 2
(-7738 2058);
DISPLAY 0.680851 (-7738 2058);
PAINT GREEN (-7738 2058);
FORCEPROP 2 LAST CDS_LIB standard
J 0
(-7800 2050);
DISPLAY INVISIBLE (-7800 2050);
FORCEPROP 1 LAST BODY_TYPE PLUMBING
J 2
(-7800 2100);
DISPLAY 0.872340 (-7800 2100);
PAINT GREEN (-7800 2100);
DISPLAY INVISIBLE (-7800 2100);
FORCEPROP 1 LAST HDL_TAP TRUE
J 2
(-8125 1925);
DISPLAY 0.872340 (-8125 1925);
DISPLAY INVISIBLE (-8125 1925);
FORCEPROP 1 LAST PATH I89
J 2
(-7798 2050);
DISPLAY 0.872340 (-7798 2050);
PAINT GREEN (-7798 2050);
DISPLAY INVISIBLE (-7798 2050);
FORCEADD TAP..1
R 2
(-3450 1200);
FORCEPROP 3 LASTPIN (-3400 1200) SIG_NAME P5E_CPU0_P3_TX_BUF_DN<4>
J 0
(-3390 1210);
DISPLAY 0.659574 (-3390 1210);
PAINT MONO (-3390 1210);
DISPLAY INVISIBLE (-3390 1210);
FORCEPROP 1 LASTPIN (-3400 1200) BN 4
J 2
(-3388 1208);
DISPLAY 0.680851 (-3388 1208);
PAINT GREEN (-3388 1208);
FORCEPROP 2 LAST CDS_LIB standard
J 0
(-3450 1200);
DISPLAY INVISIBLE (-3450 1200);
FORCEPROP 1 LAST BODY_TYPE PLUMBING
J 2
(-3450 1250);
DISPLAY 0.872340 (-3450 1250);
PAINT GREEN (-3450 1250);
DISPLAY INVISIBLE (-3450 1250);
FORCEPROP 1 LAST HDL_TAP TRUE
J 2
(-3775 1075);
DISPLAY 0.872340 (-3775 1075);
DISPLAY INVISIBLE (-3775 1075);
FORCEPROP 1 LAST PATH I9
J 2
(-3448 1200);
DISPLAY 0.872340 (-3448 1200);
PAINT GREEN (-3448 1200);
DISPLAY INVISIBLE (-3448 1200);
FORCEADD Q_CAP_DIFFBUS..2
R 2
(-7075 600);
FORCEPROP 1 LAST LOCATION C6628
J 2
(-6800 600);
DISPLAY 0.723404 (-6800 600);
PAINT GREEN (-6800 600);
FORCEPROP 2 LAST $SEC 1
J 2
(-6900 675);
DISPLAY 0.680851 (-6900 675);
PAINT MONO (-6900 675);
DISPLAY INVISIBLE (-6900 675);
FORCEPROP 2 LAST CDS_SEC 1
J 2
(-6900 675);
DISPLAY 0.680851 (-6900 675);
DISPLAY INVISIBLE (-6900 675);
FORCEPROP 2 LASTPIN (-7000 600) $PN 1
J 0
(-6990 610);
DISPLAY 0.808511 (-6990 610);
FORCEPROP 2 LASTPIN (-7150 600) $PN 2
J 2
(-7160 610);
DISPLAY 0.808511 (-7160 610);
FORCEPROP 2 LAST VALUE DIFF BUS_0.22UF
J 2
(-7225 600);
DISPLAY 0.553191 (-7225 600);
FORCEPROP 1 LAST CDS_LMAN_SYM_OUTLINE -25,50,25,-50
J 2
(-7075 600);
DISPLAY 0.468085 (-7075 600);
PAINT GREEN (-7075 600);
DISPLAY INVISIBLE (-7075 600);
FORCEPROP 2 LAST CDS_LIB pure_quanta
J 2
(-7075 600);
DISPLAY INVISIBLE (-7075 600);
FORCEPROP 1 LAST PIN_NAMES_ROTATE TRUE
J 2
(-7075 600);
DISPLAY 0.489362 (-7075 600);
PAINT GREEN (-7075 600);
DISPLAY INVISIBLE (-7075 600);
FORCEPROP 2 LAST VOLTAGE 6.3V
J 2
(-7425 650);
DISPLAY 0.553191 (-7425 650);
DISPLAY INVISIBLE (-7425 650);
FORCEPROP 1 LAST MATERIAL X6S
J 2
(-7066 679);
DISPLAY 0.574468 (-7066 679);
PAINT GREEN (-7066 679);
DISPLAY INVISIBLE (-7066 679);
FORCEPROP 2 LAST PACK_TYPE C0201
J 2
(-7250 650);
DISPLAY 0.553191 (-7250 650);
DISPLAY INVISIBLE (-7250 650);
FORCEPROP 2 LAST TOLERANCE 20%
J 2
(-7150 650);
DISPLAY 0.553191 (-7150 650);
DISPLAY INVISIBLE (-7150 650);
FORCEPROP 1 LAST PATH I90
J 2
(-7075 600);
DISPLAY 0.723404 (-7075 600);
DISPLAY INVISIBLE (-7075 600);
FORCEPROP 1 LAST PART_NUMBER SP_CH4221MEE01
J 2
(-7191 688);
DISPLAY 0.574468 (-7191 688);
PAINT GREEN (-7191 688);
DISPLAY INVISIBLE (-7191 688);
FORCEPROP 1 LAST LOCATION C6628
J 0
(-6825 675);
DISPLAY 1.021277 (-6825 675);
DISPLAY INVISIBLE (-6825 675);
FORCEADD Q_CAP_DIFFBUS..2
R 2
(-7075 850);
FORCEPROP 1 LAST LOCATION C6625
J 2
(-6800 850);
DISPLAY 0.723404 (-6800 850);
PAINT GREEN (-6800 850);
FORCEPROP 2 LAST $SEC 1
J 2
(-6900 925);
DISPLAY 0.680851 (-6900 925);
PAINT MONO (-6900 925);
DISPLAY INVISIBLE (-6900 925);
FORCEPROP 2 LAST CDS_SEC 1
J 2
(-6900 925);
DISPLAY 0.680851 (-6900 925);
DISPLAY INVISIBLE (-6900 925);
FORCEPROP 2 LASTPIN (-7000 850) $PN 1
J 0
(-6990 860);
DISPLAY 0.808511 (-6990 860);
FORCEPROP 2 LASTPIN (-7150 850) $PN 2
J 2
(-7160 860);
DISPLAY 0.808511 (-7160 860);
FORCEPROP 2 LAST VALUE DIFF BUS_0.22UF
J 2
(-7225 850);
DISPLAY 0.553191 (-7225 850);
FORCEPROP 2 LAST CDS_LIB pure_quanta
J 2
(-7075 850);
DISPLAY INVISIBLE (-7075 850);
FORCEPROP 1 LAST CDS_LMAN_SYM_OUTLINE -25,50,25,-50
J 2
(-7075 850);
DISPLAY 0.468085 (-7075 850);
PAINT GREEN (-7075 850);
DISPLAY INVISIBLE (-7075 850);
FORCEPROP 1 LAST PIN_NAMES_ROTATE TRUE
J 2
(-7075 850);
DISPLAY 0.489362 (-7075 850);
PAINT GREEN (-7075 850);
DISPLAY INVISIBLE (-7075 850);
FORCEPROP 2 LAST VOLTAGE 6.3V
J 2
(-7425 900);
DISPLAY 0.553191 (-7425 900);
DISPLAY INVISIBLE (-7425 900);
FORCEPROP 1 LAST MATERIAL X6S
J 2
(-7066 929);
DISPLAY 0.574468 (-7066 929);
PAINT GREEN (-7066 929);
DISPLAY INVISIBLE (-7066 929);
FORCEPROP 2 LAST PACK_TYPE C0201
J 2
(-7250 900);
DISPLAY 0.553191 (-7250 900);
DISPLAY INVISIBLE (-7250 900);
FORCEPROP 2 LAST TOLERANCE 20%
J 2
(-7150 900);
DISPLAY 0.553191 (-7150 900);
DISPLAY INVISIBLE (-7150 900);
FORCEPROP 1 LAST PATH I91
J 2
(-7075 850);
DISPLAY 0.723404 (-7075 850);
DISPLAY INVISIBLE (-7075 850);
FORCEPROP 1 LAST PART_NUMBER SP_CH4221MEE01
J 2
(-7191 938);
DISPLAY 0.574468 (-7191 938);
PAINT GREEN (-7191 938);
DISPLAY INVISIBLE (-7191 938);
FORCEPROP 1 LAST LOCATION C6625
J 0
(-6825 925);
DISPLAY 1.021277 (-6825 925);
DISPLAY INVISIBLE (-6825 925);
FORCEADD Q_CAP_DIFFBUS..2
R 2
(-7075 800);
FORCEPROP 1 LAST LOCATION C6626
J 2
(-6800 800);
DISPLAY 0.723404 (-6800 800);
PAINT GREEN (-6800 800);
FORCEPROP 2 LAST $SEC 1
J 2
(-6900 875);
DISPLAY 0.680851 (-6900 875);
PAINT MONO (-6900 875);
DISPLAY INVISIBLE (-6900 875);
FORCEPROP 2 LAST CDS_SEC 1
J 2
(-6900 875);
DISPLAY 0.680851 (-6900 875);
DISPLAY INVISIBLE (-6900 875);
FORCEPROP 2 LASTPIN (-7000 800) $PN 1
J 0
(-6990 810);
DISPLAY 0.808511 (-6990 810);
FORCEPROP 2 LASTPIN (-7150 800) $PN 2
J 2
(-7160 810);
DISPLAY 0.808511 (-7160 810);
FORCEPROP 2 LAST VALUE DIFF BUS_0.22UF
J 2
(-7225 800);
DISPLAY 0.553191 (-7225 800);
FORCEPROP 1 LAST CDS_LMAN_SYM_OUTLINE -25,50,25,-50
J 2
(-7075 800);
DISPLAY 0.468085 (-7075 800);
PAINT GREEN (-7075 800);
DISPLAY INVISIBLE (-7075 800);
FORCEPROP 2 LAST CDS_LIB pure_quanta
J 2
(-7075 800);
DISPLAY INVISIBLE (-7075 800);
FORCEPROP 1 LAST PIN_NAMES_ROTATE TRUE
J 2
(-7075 800);
DISPLAY 0.489362 (-7075 800);
PAINT GREEN (-7075 800);
DISPLAY INVISIBLE (-7075 800);
FORCEPROP 2 LAST VOLTAGE 6.3V
J 2
(-7425 850);
DISPLAY 0.553191 (-7425 850);
DISPLAY INVISIBLE (-7425 850);
FORCEPROP 1 LAST MATERIAL X6S
J 2
(-7066 879);
DISPLAY 0.574468 (-7066 879);
PAINT GREEN (-7066 879);
DISPLAY INVISIBLE (-7066 879);
FORCEPROP 2 LAST PACK_TYPE C0201
J 2
(-7250 850);
DISPLAY 0.553191 (-7250 850);
DISPLAY INVISIBLE (-7250 850);
FORCEPROP 2 LAST TOLERANCE 20%
J 2
(-7150 850);
DISPLAY 0.553191 (-7150 850);
DISPLAY INVISIBLE (-7150 850);
FORCEPROP 1 LAST PATH I92
J 2
(-7075 800);
DISPLAY 0.723404 (-7075 800);
DISPLAY INVISIBLE (-7075 800);
FORCEPROP 1 LAST PART_NUMBER SP_CH4221MEE01
J 2
(-7191 888);
DISPLAY 0.574468 (-7191 888);
PAINT GREEN (-7191 888);
DISPLAY INVISIBLE (-7191 888);
FORCEPROP 1 LAST LOCATION C6626
J 0
(-6825 875);
DISPLAY 1.021277 (-6825 875);
DISPLAY INVISIBLE (-6825 875);
FORCEADD Q_CAP_DIFFBUS..2
R 2
(-7075 650);
FORCEPROP 1 LAST LOCATION C6627
J 2
(-6800 650);
DISPLAY 0.723404 (-6800 650);
PAINT GREEN (-6800 650);
FORCEPROP 2 LAST $SEC 1
J 2
(-6900 725);
DISPLAY 0.680851 (-6900 725);
PAINT MONO (-6900 725);
DISPLAY INVISIBLE (-6900 725);
FORCEPROP 2 LAST CDS_SEC 1
J 2
(-6900 725);
DISPLAY 0.680851 (-6900 725);
DISPLAY INVISIBLE (-6900 725);
FORCEPROP 2 LASTPIN (-7000 650) $PN 1
J 0
(-6990 660);
DISPLAY 0.808511 (-6990 660);
FORCEPROP 2 LASTPIN (-7150 650) $PN 2
J 2
(-7160 660);
DISPLAY 0.808511 (-7160 660);
FORCEPROP 2 LAST VALUE DIFF BUS_0.22UF
J 2
(-7225 650);
DISPLAY 0.553191 (-7225 650);
FORCEPROP 1 LAST CDS_LMAN_SYM_OUTLINE -25,50,25,-50
J 2
(-7075 650);
DISPLAY 0.468085 (-7075 650);
PAINT GREEN (-7075 650);
DISPLAY INVISIBLE (-7075 650);
FORCEPROP 2 LAST CDS_LIB pure_quanta
J 2
(-7075 650);
DISPLAY INVISIBLE (-7075 650);
FORCEPROP 1 LAST PIN_NAMES_ROTATE TRUE
J 2
(-7075 650);
DISPLAY 0.489362 (-7075 650);
PAINT GREEN (-7075 650);
DISPLAY INVISIBLE (-7075 650);
FORCEPROP 2 LAST VOLTAGE 6.3V
J 2
(-7425 700);
DISPLAY 0.553191 (-7425 700);
DISPLAY INVISIBLE (-7425 700);
FORCEPROP 1 LAST MATERIAL X6S
J 2
(-7066 729);
DISPLAY 0.574468 (-7066 729);
PAINT GREEN (-7066 729);
DISPLAY INVISIBLE (-7066 729);
FORCEPROP 2 LAST PACK_TYPE C0201
J 2
(-7250 700);
DISPLAY 0.553191 (-7250 700);
DISPLAY INVISIBLE (-7250 700);
FORCEPROP 2 LAST TOLERANCE 20%
J 2
(-7150 700);
DISPLAY 0.553191 (-7150 700);
DISPLAY INVISIBLE (-7150 700);
FORCEPROP 1 LAST PATH I93
J 2
(-7075 650);
DISPLAY 0.723404 (-7075 650);
DISPLAY INVISIBLE (-7075 650);
FORCEPROP 1 LAST PART_NUMBER SP_CH4221MEE01
J 2
(-7191 738);
DISPLAY 0.574468 (-7191 738);
PAINT GREEN (-7191 738);
DISPLAY INVISIBLE (-7191 738);
FORCEPROP 1 LAST LOCATION C6627
J 0
(-6825 725);
DISPLAY 1.021277 (-6825 725);
DISPLAY INVISIBLE (-6825 725);
FORCEADD Q_CAP_DIFFBUS..2
R 2
(-7075 1050);
FORCEPROP 1 LAST LOCATION C6623
J 2
(-6800 1050);
DISPLAY 0.723404 (-6800 1050);
PAINT GREEN (-6800 1050);
FORCEPROP 2 LAST $SEC 1
J 2
(-6900 1125);
DISPLAY 0.680851 (-6900 1125);
PAINT MONO (-6900 1125);
DISPLAY INVISIBLE (-6900 1125);
FORCEPROP 2 LAST CDS_SEC 1
J 2
(-6900 1125);
DISPLAY 0.680851 (-6900 1125);
DISPLAY INVISIBLE (-6900 1125);
FORCEPROP 2 LASTPIN (-7000 1050) $PN 1
J 0
(-6990 1060);
DISPLAY 0.808511 (-6990 1060);
FORCEPROP 2 LASTPIN (-7150 1050) $PN 2
J 2
(-7160 1060);
DISPLAY 0.808511 (-7160 1060);
FORCEPROP 2 LAST VALUE DIFF BUS_0.22UF
J 2
(-7225 1050);
DISPLAY 0.553191 (-7225 1050);
FORCEPROP 1 LAST CDS_LMAN_SYM_OUTLINE -25,50,25,-50
J 2
(-7075 1050);
DISPLAY 0.468085 (-7075 1050);
PAINT GREEN (-7075 1050);
DISPLAY INVISIBLE (-7075 1050);
FORCEPROP 2 LAST CDS_LIB pure_quanta
J 2
(-7075 1050);
DISPLAY INVISIBLE (-7075 1050);
FORCEPROP 1 LAST PIN_NAMES_ROTATE TRUE
J 2
(-7075 1050);
DISPLAY 0.489362 (-7075 1050);
PAINT GREEN (-7075 1050);
DISPLAY INVISIBLE (-7075 1050);
FORCEPROP 2 LAST VOLTAGE 6.3V
J 2
(-7425 1100);
DISPLAY 0.553191 (-7425 1100);
DISPLAY INVISIBLE (-7425 1100);
FORCEPROP 1 LAST MATERIAL X6S
J 2
(-7066 1129);
DISPLAY 0.574468 (-7066 1129);
PAINT GREEN (-7066 1129);
DISPLAY INVISIBLE (-7066 1129);
FORCEPROP 2 LAST PACK_TYPE C0201
J 2
(-7250 1100);
DISPLAY 0.553191 (-7250 1100);
DISPLAY INVISIBLE (-7250 1100);
FORCEPROP 2 LAST TOLERANCE 20%
J 2
(-7150 1100);
DISPLAY 0.553191 (-7150 1100);
DISPLAY INVISIBLE (-7150 1100);
FORCEPROP 1 LAST PATH I94
J 2
(-7075 1050);
DISPLAY 0.723404 (-7075 1050);
DISPLAY INVISIBLE (-7075 1050);
FORCEPROP 1 LAST PART_NUMBER SP_CH4221MEE01
J 2
(-7191 1138);
DISPLAY 0.574468 (-7191 1138);
PAINT GREEN (-7191 1138);
DISPLAY INVISIBLE (-7191 1138);
FORCEPROP 1 LAST LOCATION C6623
J 0
(-6825 1125);
DISPLAY 1.021277 (-6825 1125);
DISPLAY INVISIBLE (-6825 1125);
FORCEADD Q_CAP_DIFFBUS..2
R 2
(-7075 1000);
FORCEPROP 1 LAST LOCATION C6624
J 2
(-6800 1000);
DISPLAY 0.723404 (-6800 1000);
PAINT GREEN (-6800 1000);
FORCEPROP 2 LAST $SEC 1
J 2
(-6900 1075);
DISPLAY 0.680851 (-6900 1075);
PAINT MONO (-6900 1075);
DISPLAY INVISIBLE (-6900 1075);
FORCEPROP 2 LAST CDS_SEC 1
J 2
(-6900 1075);
DISPLAY 0.680851 (-6900 1075);
DISPLAY INVISIBLE (-6900 1075);
FORCEPROP 2 LASTPIN (-7000 1000) $PN 1
J 0
(-6990 1010);
DISPLAY 0.808511 (-6990 1010);
FORCEPROP 2 LASTPIN (-7150 1000) $PN 2
J 2
(-7160 1010);
DISPLAY 0.808511 (-7160 1010);
FORCEPROP 2 LAST VALUE DIFF BUS_0.22UF
J 2
(-7225 1000);
DISPLAY 0.553191 (-7225 1000);
FORCEPROP 1 LAST CDS_LMAN_SYM_OUTLINE -25,50,25,-50
J 2
(-7075 1000);
DISPLAY 0.468085 (-7075 1000);
PAINT GREEN (-7075 1000);
DISPLAY INVISIBLE (-7075 1000);
FORCEPROP 2 LAST CDS_LIB pure_quanta
J 2
(-7075 1000);
DISPLAY INVISIBLE (-7075 1000);
FORCEPROP 1 LAST PIN_NAMES_ROTATE TRUE
J 2
(-7075 1000);
DISPLAY 0.489362 (-7075 1000);
PAINT GREEN (-7075 1000);
DISPLAY INVISIBLE (-7075 1000);
FORCEPROP 2 LAST VOLTAGE 6.3V
J 2
(-7425 1050);
DISPLAY 0.553191 (-7425 1050);
DISPLAY INVISIBLE (-7425 1050);
FORCEPROP 1 LAST MATERIAL X6S
J 2
(-7066 1079);
DISPLAY 0.574468 (-7066 1079);
PAINT GREEN (-7066 1079);
DISPLAY INVISIBLE (-7066 1079);
FORCEPROP 2 LAST PACK_TYPE C0201
J 2
(-7250 1050);
DISPLAY 0.553191 (-7250 1050);
DISPLAY INVISIBLE (-7250 1050);
FORCEPROP 2 LAST TOLERANCE 20%
J 2
(-7150 1050);
DISPLAY 0.553191 (-7150 1050);
DISPLAY INVISIBLE (-7150 1050);
FORCEPROP 1 LAST PATH I95
J 2
(-7075 1000);
DISPLAY 0.723404 (-7075 1000);
DISPLAY INVISIBLE (-7075 1000);
FORCEPROP 1 LAST PART_NUMBER SP_CH4221MEE01
J 2
(-7191 1088);
DISPLAY 0.574468 (-7191 1088);
PAINT GREEN (-7191 1088);
DISPLAY INVISIBLE (-7191 1088);
FORCEPROP 1 LAST LOCATION C6624
J 0
(-6825 1075);
DISPLAY 1.021277 (-6825 1075);
DISPLAY INVISIBLE (-6825 1075);
FORCEADD Q_CAP_DIFFBUS..2
R 2
(-7075 1250);
FORCEPROP 1 LAST LOCATION C6621
J 2
(-6800 1250);
DISPLAY 0.723404 (-6800 1250);
PAINT GREEN (-6800 1250);
FORCEPROP 2 LAST $SEC 1
J 2
(-6900 1325);
DISPLAY 0.680851 (-6900 1325);
PAINT MONO (-6900 1325);
DISPLAY INVISIBLE (-6900 1325);
FORCEPROP 2 LAST CDS_SEC 1
J 2
(-6900 1325);
DISPLAY 0.680851 (-6900 1325);
DISPLAY INVISIBLE (-6900 1325);
FORCEPROP 2 LASTPIN (-7000 1250) $PN 1
J 0
(-6990 1260);
DISPLAY 0.808511 (-6990 1260);
FORCEPROP 2 LASTPIN (-7150 1250) $PN 2
J 2
(-7160 1260);
DISPLAY 0.808511 (-7160 1260);
FORCEPROP 2 LAST VALUE DIFF BUS_0.22UF
J 2
(-7225 1250);
DISPLAY 0.553191 (-7225 1250);
FORCEPROP 2 LAST CDS_LIB pure_quanta
J 2
(-7075 1250);
DISPLAY INVISIBLE (-7075 1250);
FORCEPROP 1 LAST CDS_LMAN_SYM_OUTLINE -25,50,25,-50
J 2
(-7075 1250);
DISPLAY 0.468085 (-7075 1250);
PAINT GREEN (-7075 1250);
DISPLAY INVISIBLE (-7075 1250);
FORCEPROP 1 LAST PIN_NAMES_ROTATE TRUE
J 2
(-7075 1250);
DISPLAY 0.489362 (-7075 1250);
PAINT GREEN (-7075 1250);
DISPLAY INVISIBLE (-7075 1250);
FORCEPROP 2 LAST VOLTAGE 6.3V
J 2
(-7425 1300);
DISPLAY 0.553191 (-7425 1300);
DISPLAY INVISIBLE (-7425 1300);
FORCEPROP 1 LAST MATERIAL X6S
J 2
(-7066 1329);
DISPLAY 0.574468 (-7066 1329);
PAINT GREEN (-7066 1329);
DISPLAY INVISIBLE (-7066 1329);
FORCEPROP 2 LAST PACK_TYPE C0201
J 2
(-7250 1300);
DISPLAY 0.553191 (-7250 1300);
DISPLAY INVISIBLE (-7250 1300);
FORCEPROP 2 LAST TOLERANCE 20%
J 2
(-7150 1300);
DISPLAY 0.553191 (-7150 1300);
DISPLAY INVISIBLE (-7150 1300);
FORCEPROP 1 LAST PATH I96
J 2
(-7075 1250);
DISPLAY 0.723404 (-7075 1250);
DISPLAY INVISIBLE (-7075 1250);
FORCEPROP 1 LAST PART_NUMBER SP_CH4221MEE01
J 2
(-7191 1338);
DISPLAY 0.574468 (-7191 1338);
PAINT GREEN (-7191 1338);
DISPLAY INVISIBLE (-7191 1338);
FORCEPROP 1 LAST LOCATION C6621
J 0
(-6825 1325);
DISPLAY 1.021277 (-6825 1325);
DISPLAY INVISIBLE (-6825 1325);
FORCEADD Q_CAP_DIFFBUS..2
R 2
(-7075 1200);
FORCEPROP 1 LAST LOCATION C6622
J 2
(-6800 1200);
DISPLAY 0.723404 (-6800 1200);
PAINT GREEN (-6800 1200);
FORCEPROP 2 LAST $SEC 1
J 2
(-6900 1275);
DISPLAY 0.680851 (-6900 1275);
PAINT MONO (-6900 1275);
DISPLAY INVISIBLE (-6900 1275);
FORCEPROP 2 LAST CDS_SEC 1
J 2
(-6900 1275);
DISPLAY 0.680851 (-6900 1275);
DISPLAY INVISIBLE (-6900 1275);
FORCEPROP 2 LASTPIN (-7000 1200) $PN 1
J 0
(-6990 1210);
DISPLAY 0.808511 (-6990 1210);
FORCEPROP 2 LASTPIN (-7150 1200) $PN 2
J 2
(-7160 1210);
DISPLAY 0.808511 (-7160 1210);
FORCEPROP 2 LAST VALUE DIFF BUS_0.22UF
J 2
(-7225 1200);
DISPLAY 0.553191 (-7225 1200);
FORCEPROP 2 LAST CDS_LIB pure_quanta
J 2
(-7075 1200);
DISPLAY INVISIBLE (-7075 1200);
FORCEPROP 1 LAST CDS_LMAN_SYM_OUTLINE -25,50,25,-50
J 2
(-7075 1200);
DISPLAY 0.468085 (-7075 1200);
PAINT GREEN (-7075 1200);
DISPLAY INVISIBLE (-7075 1200);
FORCEPROP 1 LAST PIN_NAMES_ROTATE TRUE
J 2
(-7075 1200);
DISPLAY 0.489362 (-7075 1200);
PAINT GREEN (-7075 1200);
DISPLAY INVISIBLE (-7075 1200);
FORCEPROP 2 LAST VOLTAGE 6.3V
J 2
(-7425 1250);
DISPLAY 0.553191 (-7425 1250);
DISPLAY INVISIBLE (-7425 1250);
FORCEPROP 1 LAST MATERIAL X6S
J 2
(-7066 1279);
DISPLAY 0.574468 (-7066 1279);
PAINT GREEN (-7066 1279);
DISPLAY INVISIBLE (-7066 1279);
FORCEPROP 2 LAST PACK_TYPE C0201
J 2
(-7250 1250);
DISPLAY 0.553191 (-7250 1250);
DISPLAY INVISIBLE (-7250 1250);
FORCEPROP 2 LAST TOLERANCE 20%
J 2
(-7150 1250);
DISPLAY 0.553191 (-7150 1250);
DISPLAY INVISIBLE (-7150 1250);
FORCEPROP 1 LAST PATH I97
J 2
(-7075 1200);
DISPLAY 0.723404 (-7075 1200);
DISPLAY INVISIBLE (-7075 1200);
FORCEPROP 1 LAST PART_NUMBER SP_CH4221MEE01
J 2
(-7191 1288);
DISPLAY 0.574468 (-7191 1288);
PAINT GREEN (-7191 1288);
DISPLAY INVISIBLE (-7191 1288);
FORCEPROP 1 LAST LOCATION C6622
J 0
(-6825 1275);
DISPLAY 1.021277 (-6825 1275);
DISPLAY INVISIBLE (-6825 1275);
FORCEADD Q_CAP_DIFFBUS..2
R 2
(-7075 1400);
FORCEPROP 1 LAST LOCATION C6620
J 2
(-6800 1400);
DISPLAY 0.723404 (-6800 1400);
PAINT GREEN (-6800 1400);
FORCEPROP 2 LAST $SEC 1
J 2
(-6900 1475);
DISPLAY 0.680851 (-6900 1475);
PAINT MONO (-6900 1475);
DISPLAY INVISIBLE (-6900 1475);
FORCEPROP 2 LAST CDS_SEC 1
J 2
(-6900 1475);
DISPLAY 0.680851 (-6900 1475);
DISPLAY INVISIBLE (-6900 1475);
FORCEPROP 2 LASTPIN (-7000 1400) $PN 1
J 0
(-6990 1410);
DISPLAY 0.808511 (-6990 1410);
FORCEPROP 2 LASTPIN (-7150 1400) $PN 2
J 2
(-7160 1410);
DISPLAY 0.808511 (-7160 1410);
FORCEPROP 2 LAST VALUE DIFF BUS_0.22UF
J 2
(-7225 1400);
DISPLAY 0.553191 (-7225 1400);
FORCEPROP 1 LAST CDS_LMAN_SYM_OUTLINE -25,50,25,-50
J 2
(-7075 1400);
DISPLAY 0.468085 (-7075 1400);
PAINT GREEN (-7075 1400);
DISPLAY INVISIBLE (-7075 1400);
FORCEPROP 2 LAST CDS_LIB pure_quanta
J 2
(-7075 1400);
DISPLAY INVISIBLE (-7075 1400);
FORCEPROP 1 LAST PIN_NAMES_ROTATE TRUE
J 2
(-7075 1400);
DISPLAY 0.489362 (-7075 1400);
PAINT GREEN (-7075 1400);
DISPLAY INVISIBLE (-7075 1400);
FORCEPROP 2 LAST VOLTAGE 6.3V
J 2
(-7425 1450);
DISPLAY 0.553191 (-7425 1450);
DISPLAY INVISIBLE (-7425 1450);
FORCEPROP 1 LAST MATERIAL X6S
J 2
(-7066 1479);
DISPLAY 0.574468 (-7066 1479);
PAINT GREEN (-7066 1479);
DISPLAY INVISIBLE (-7066 1479);
FORCEPROP 2 LAST PACK_TYPE C0201
J 2
(-7250 1450);
DISPLAY 0.553191 (-7250 1450);
DISPLAY INVISIBLE (-7250 1450);
FORCEPROP 2 LAST TOLERANCE 20%
J 2
(-7150 1450);
DISPLAY 0.553191 (-7150 1450);
DISPLAY INVISIBLE (-7150 1450);
FORCEPROP 1 LAST PATH I98
J 2
(-7075 1400);
DISPLAY 0.723404 (-7075 1400);
DISPLAY INVISIBLE (-7075 1400);
FORCEPROP 1 LAST PART_NUMBER SP_CH4221MEE01
J 2
(-7191 1488);
DISPLAY 0.574468 (-7191 1488);
PAINT GREEN (-7191 1488);
DISPLAY INVISIBLE (-7191 1488);
FORCEPROP 1 LAST LOCATION C6620
J 0
(-6825 1475);
DISPLAY 1.021277 (-6825 1475);
DISPLAY INVISIBLE (-6825 1475);
FORCEADD Q_CAP_DIFFBUS..2
R 2
(-7075 1600);
FORCEPROP 1 LAST LOCATION C6618
J 2
(-6800 1600);
DISPLAY 0.723404 (-6800 1600);
PAINT GREEN (-6800 1600);
FORCEPROP 2 LAST $SEC 1
J 2
(-6900 1675);
DISPLAY 0.680851 (-6900 1675);
PAINT MONO (-6900 1675);
DISPLAY INVISIBLE (-6900 1675);
FORCEPROP 2 LAST CDS_SEC 1
J 2
(-6900 1675);
DISPLAY 0.680851 (-6900 1675);
DISPLAY INVISIBLE (-6900 1675);
FORCEPROP 2 LASTPIN (-7000 1600) $PN 1
J 0
(-6990 1610);
DISPLAY 0.808511 (-6990 1610);
FORCEPROP 2 LASTPIN (-7150 1600) $PN 2
J 2
(-7160 1610);
DISPLAY 0.808511 (-7160 1610);
FORCEPROP 2 LAST VALUE DIFF BUS_0.22UF
J 2
(-7225 1600);
DISPLAY 0.553191 (-7225 1600);
FORCEPROP 1 LAST CDS_LMAN_SYM_OUTLINE -25,50,25,-50
J 2
(-7075 1600);
DISPLAY 0.468085 (-7075 1600);
PAINT GREEN (-7075 1600);
DISPLAY INVISIBLE (-7075 1600);
FORCEPROP 2 LAST CDS_LIB pure_quanta
J 2
(-7075 1600);
DISPLAY INVISIBLE (-7075 1600);
FORCEPROP 1 LAST PIN_NAMES_ROTATE TRUE
J 2
(-7075 1600);
DISPLAY 0.489362 (-7075 1600);
PAINT GREEN (-7075 1600);
DISPLAY INVISIBLE (-7075 1600);
FORCEPROP 2 LAST VOLTAGE 6.3V
J 2
(-7425 1650);
DISPLAY 0.553191 (-7425 1650);
DISPLAY INVISIBLE (-7425 1650);
FORCEPROP 1 LAST MATERIAL X6S
J 2
(-7066 1679);
DISPLAY 0.574468 (-7066 1679);
PAINT GREEN (-7066 1679);
DISPLAY INVISIBLE (-7066 1679);
FORCEPROP 2 LAST PACK_TYPE C0201
J 2
(-7250 1650);
DISPLAY 0.553191 (-7250 1650);
DISPLAY INVISIBLE (-7250 1650);
FORCEPROP 2 LAST TOLERANCE 20%
J 2
(-7150 1650);
DISPLAY 0.553191 (-7150 1650);
DISPLAY INVISIBLE (-7150 1650);
FORCEPROP 1 LAST PATH I99
J 2
(-7075 1600);
DISPLAY 0.723404 (-7075 1600);
DISPLAY INVISIBLE (-7075 1600);
FORCEPROP 1 LAST PART_NUMBER SP_CH4221MEE01
J 2
(-7191 1688);
DISPLAY 0.574468 (-7191 1688);
PAINT GREEN (-7191 1688);
DISPLAY INVISIBLE (-7191 1688);
FORCEPROP 1 LAST LOCATION C6618
J 0
(-6825 1675);
DISPLAY 1.021277 (-6825 1675);
DISPLAY INVISIBLE (-6825 1675);
FORCEADD QUANTA_TITLE_BLOCK_C..1
(0 0);
FORCEPROP 0 LAST CDS_CON_LAST_MODIFIED Thu Sep 14 16:12:54 2023
J 0
(-1885 15);
DISPLAY INVISIBLE (-1885 15);
FORCEPROP 1 LAST CUSTOM_TXT_CDS <CON_LAST_MODIFIED>
J 0
(-1885 15);
DISPLAY 0.978723 (-1885 15);
FORCEPROP 2 LAST CUSTOM_TXT_CDS <XR_PAGE_TITLE>
J 0
(-7890 5250);
DISPLAY 0.638298 (-7890 5250);
PAINT PINK (-7890 5250);
DISPLAY INVISIBLE (-7890 5250);
FORCEPROP 1 LAST CUSTOM_TXT_CDS <NAME_2>
J 0
(-3175 50);
FORCEPROP 1 LAST CUSTOM_TXT_CDS <NAME_1>
J 0
(-3175 175);
FORCEPROP 1 LAST CUSTOM_TXT_CDS <Q_NUMBER>
J 0
(-1403 103);
DISPLAY 1.212766 (-1403 103);
FORCEPROP 1 LAST CUSTOM_TXT_CDS <Q_PROJ>
J 0
(-2382 102);
DISPLAY 1.212766 (-2382 102);
FORCEPROP 1 LAST CUSTOM_TXT_CDS <Q_REV>
J 0
(-184 103);
DISPLAY 1.212766 (-184 103);
FORCEPROP 1 LAST CUSTOM_TXT_CDS <CON_PAGE_NUM> OF <CON_TOTAL_PAGES>
J 0
(-446 18);
DISPLAY 0.978723 (-446 18);
FORCEPROP 1 LAST Q_TITLE RETIMER_CPU0_P3(4)
J 0
(-9366 26);
DISPLAY 2.446809 (-9366 26);
PAINT GREEN (-9366 26);
FORCEPROP 2 LAST PAGE_BORDER TRUE
J 0
(-7890 5250);
DISPLAY 0.638298 (-7890 5250);
PAINT PINK (-7890 5250);
DISPLAY INVISIBLE (-7890 5250);
FORCEPROP 1 LAST CDS_LMAN_SYM_OUTLINE -9475,6775,100,-125
J 0
(0 0);
DISPLAY 0.468085 (0 0);
PAINT GREEN (0 0);
DISPLAY INVISIBLE (0 0);
FORCEPROP 2 LAST CDS_LIB pure_quanta
J 0
(0 0);
DISPLAY INVISIBLE (0 0);
FORCEPROP 2 LAST CDS_XR_PAGE_TITLE CR-309 : @T6G_MB_LIB.T6G(SCH_1):PAGE309
J 0
(-7890 5250);
DISPLAY 0.638298 (-7890 5250);
PAINT PINK (-7890 5250);
DISPLAY INVISIBLE (-7890 5250);
FORCEPROP 1 LAST Q_DEPT BU9
J 1
(-3763 49);
DISPLAY 1.957447 (-3763 49);
PAINT GREEN (-3763 49);
DISPLAY INVISIBLE (-3763 49);
FORCEPROP 1 LAST COMMENT_BODY TRUE
J 0
(12 -13);
DISPLAY 0.978723 (12 -13);
PAINT GREEN (12 -13);
DISPLAY INVISIBLE (12 -13);
WIRE 17 -1 (-6275 2025)(-5375 2025);
FORCEPROP 2 LAST SIG_NAME P5E_CPU0_P3_TX_BUF_C_DN<15:8>
J 0
(-6285 2035);
DISPLAY 0.680851 (-6285 2035);
PAINT WHITE (-6285 2035);
WIRE 17 -1 (-3500 625)(-3500 825);
WIRE 17 -1 (-3500 825)(-3500 1025);
WIRE 17 -1 (-3500 1025)(-3500 1225);
WIRE 17 -1 (-3500 1225)(-3500 1425);
WIRE 17 -1 (-3500 1425)(-3500 1625);
WIRE 17 -1 (-3500 1625)(-3500 1825);
WIRE 17 -1 (-3500 1825)(-3500 2025);
WIRE 17 -1 (-4350 2025)(-3500 2025);
FORCEPROP 2 LAST SIG_NAME P5E_CPU0_P3_TX_BUF_DN<7:0>
J 0
(-4335 2035);
DISPLAY 0.680851 (-4335 2035);
PAINT WHITE (-4335 2035);
WIRE 17 -1 (-3250 875)(-3250 675);
WIRE 17 -1 (-3250 1075)(-3250 875);
WIRE 17 -1 (-3250 1275)(-3250 1075);
WIRE 17 -1 (-3250 1275)(-3250 1475);
WIRE 17 -1 (-3250 1675)(-3250 1475);
WIRE 17 -1 (-3250 1875)(-3250 1675);
WIRE 17 -1 (-3250 2075)(-3250 1875);
WIRE 17 -1 (-4350 2075)(-3250 2075);
FORCEPROP 2 LAST SIG_NAME P5E_CPU0_P3_TX_BUF_DP<7:0>
J 0
(-4335 2085);
DISPLAY 0.680851 (-4335 2085);
PAINT WHITE (-4335 2085);
WIRE 17 -1 (-1675 825)(-1675 625);
WIRE 17 -1 (-1675 1025)(-1675 825);
WIRE 17 -1 (-1675 1225)(-1675 1025);
WIRE 17 -1 (-1675 1225)(-1675 1425);
WIRE 17 -1 (-1675 1625)(-1675 1425);
WIRE 17 -1 (-1675 1825)(-1675 1625);
WIRE 17 -1 (-1675 2025)(-1675 1825);
FORCEPROP 2 LAST SIG_NAME P5E_CPU0_P3_TX_BUF_C_DN<7:0>
J 0
(-1685 2035);
DISPLAY 0.680851 (-1685 2035);
PAINT WHITE (-1685 2035);
WIRE 17 -1 (-1875 875)(-1875 675);
WIRE 17 -1 (-1875 1075)(-1875 875);
WIRE 17 -1 (-1875 1275)(-1875 1075);
WIRE 17 -1 (-1875 1275)(-1875 1475);
WIRE 17 -1 (-1875 1675)(-1875 1475);
WIRE 17 -1 (-1875 1875)(-1875 1675);
WIRE 17 -1 (-1875 2075)(-1875 1875);
WIRE 17 -1 (-1875 2075)(-775 2075);
FORCEPROP 2 LAST SIG_NAME P5E_CPU0_P3_TX_BUF_C_DP<7:0>
J 0
(-1685 2085);
DISPLAY 0.680851 (-1685 2085);
PAINT WHITE (-1685 2085);
WIRE 17 -1 (-8100 625)(-8100 825);
WIRE 17 -1 (-8100 825)(-8100 1025);
WIRE 17 -1 (-8100 1025)(-8100 1225);
WIRE 17 -1 (-8100 1225)(-8100 1425);
WIRE 17 -1 (-8100 1425)(-8100 1625);
WIRE 17 -1 (-8100 1625)(-8100 1825);
WIRE 17 -1 (-8100 1825)(-8100 2025);
WIRE 17 -1 (-8950 2025)(-8100 2025);
FORCEPROP 2 LAST SIG_NAME P5E_CPU0_P3_TX_BUF_DN<15:8>
J 0
(-8935 2035);
DISPLAY 0.680851 (-8935 2035);
PAINT WHITE (-8935 2035);
WIRE 17 -1 (-7850 875)(-7850 675);
WIRE 17 -1 (-7850 1075)(-7850 875);
WIRE 17 -1 (-7850 1275)(-7850 1075);
WIRE 17 -1 (-7850 1275)(-7850 1475);
WIRE 17 -1 (-7850 1675)(-7850 1475);
WIRE 17 -1 (-7850 1875)(-7850 1675);
WIRE 17 -1 (-7850 2075)(-7850 1875);
WIRE 17 -1 (-8950 2075)(-7850 2075);
FORCEPROP 2 LAST SIG_NAME P5E_CPU0_P3_TX_BUF_DP<15:8>
J 0
(-8935 2085);
DISPLAY 0.680851 (-8935 2085);
PAINT WHITE (-8935 2085);
WIRE 17 -1 (-6275 825)(-6275 625);
WIRE 17 -1 (-6275 1025)(-6275 825);
WIRE 17 -1 (-6275 1225)(-6275 1025);
WIRE 17 -1 (-6275 1225)(-6275 1425);
WIRE 17 -1 (-6275 1625)(-6275 1425);
WIRE 17 -1 (-6275 1825)(-6275 1625);
WIRE 17 -1 (-6275 2025)(-6275 1825);
WIRE 17 -1 (-6475 875)(-6475 675);
WIRE 17 -1 (-6475 1075)(-6475 875);
WIRE 17 -1 (-6475 1275)(-6475 1075);
WIRE 17 -1 (-6475 1275)(-6475 1475);
WIRE 17 -1 (-6475 1675)(-6475 1475);
WIRE 17 -1 (-6475 1875)(-6475 1675);
WIRE 17 -1 (-6475 2075)(-6475 1875);
WIRE 17 -1 (-6475 2075)(-5375 2075);
FORCEPROP 2 LAST SIG_NAME P5E_CPU0_P3_TX_BUF_C_DP<15:8>
J 0
(-6285 2085);
DISPLAY 0.680851 (-6285 2085);
PAINT WHITE (-6285 2085);
WIRE 17 -1 (-6800 4300)(-6800 3950);
WIRE 17 -1 (-6800 4300)(-6800 4650);
WIRE 17 -1 (-6800 3950)(-6800 3600);
WIRE 17 -1 (-6800 3600)(-6800 3250);
WIRE 17 -1 (-6800 5000)(-6800 4650);
WIRE 17 -1 (-6800 5350)(-6800 5000);
WIRE 17 -1 (-6800 5700)(-6800 5350);
FORCEPROP 2 LAST SIG_NAME P5E_CPU0_P3_TX_BUF_DN<15:8>
J 0
(-6810 5710);
DISPLAY 0.680851 (-6810 5710);
PAINT WHITE (-6810 5710);
WIRE 17 -1 (-7000 4050)(-7000 3700);
WIRE 17 -1 (-7000 4400)(-7000 4050);
WIRE 17 -1 (-7000 3700)(-7000 3350);
WIRE 17 -1 (-7000 4400)(-7000 4750);
WIRE 17 -1 (-7000 5100)(-7000 4750);
WIRE 17 -1 (-7000 5450)(-7000 5100);
WIRE 17 -1 (-7000 5800)(-7000 5450);
WIRE 17 -1 (-7000 5800)(-5900 5800);
FORCEPROP 2 LAST SIG_NAME P5E_CPU0_P3_TX_BUF_DP<15:8>
J 0
(-6810 5810);
DISPLAY 0.680851 (-6810 5810);
PAINT WHITE (-6810 5810);
WIRE 17 -1 (-1625 5325)(-1625 4975);
WIRE 17 -1 (-1625 5675)(-1625 5325);
FORCEPROP 2 LAST SIG_NAME P5E_CPU0_P3_TX_BUF_DN<7:0>
J 0
(-1635 5685);
DISPLAY 0.680851 (-1635 5685);
PAINT WHITE (-1635 5685);
WIRE 17 -1 (-1625 3575)(-1625 3225);
WIRE 17 -1 (-1625 3925)(-1625 3575);
WIRE 17 -1 (-1625 4275)(-1625 3925);
WIRE 17 -1 (-1625 4275)(-1625 4625);
WIRE 17 -1 (-1625 4975)(-1625 4625);
WIRE 17 -1 (-1825 3675)(-1825 3325);
WIRE 17 -1 (-1825 4025)(-1825 3675);
WIRE 17 -1 (-1825 4375)(-1825 4025);
WIRE 17 -1 (-1825 4375)(-1825 4725);
WIRE 17 -1 (-1825 5075)(-1825 4725);
WIRE 17 -1 (-1825 5425)(-1825 5075);
WIRE 17 -1 (-1825 5775)(-1825 5425);
WIRE 17 -1 (-1825 5775)(-725 5775);
FORCEPROP 2 LAST SIG_NAME P5E_CPU0_P3_TX_BUF_DP<7:0>
J 0
(-1635 5785);
DISPLAY 0.680851 (-1635 5785);
PAINT WHITE (-1635 5785);
WIRE 17 -1 (-1675 2025)(-775 2025);
WIRE 17 -1 (-6800 5700)(-5925 5700);
WIRE 17 -1 (-1625 5675)(-750 5675);
WIRE 16 -1 (-7325 4025)(-7100 4025);
WIRE 16 -1 (-7325 5075)(-7100 5075);
WIRE 16 -1 (-7325 4375)(-7100 4375);
WIRE 16 -1 (-7325 4725)(-7100 4725);
WIRE 16 -1 (-7325 4975)(-6900 4975);
WIRE 16 -1 (-2150 3650)(-1925 3650);
WIRE 16 -1 (-2150 4000)(-1925 4000);
WIRE 16 -1 (-2150 5050)(-1925 5050);
WIRE 16 -1 (-2150 4350)(-1925 4350);
WIRE 16 -1 (-2150 4600)(-1725 4600);
WIRE 16 -1 (-2150 5750)(-1925 5750);
WIRE 16 -1 (-2150 4700)(-1925 4700);
WIRE 16 -1 (-2150 3900)(-1725 3900);
WIRE 16 -1 (-7325 5425)(-7100 5425);
WIRE 16 -1 (-2150 5400)(-1925 5400);
WIRE 16 -1 (-7325 5775)(-7100 5775);
WIRE 16 -1 (-2150 5650)(-1725 5650);
WIRE 16 -1 (-7325 3225)(-6900 3225);
WIRE 16 -1 (-7325 4625)(-6900 4625);
WIRE 16 -1 (-7325 5325)(-6900 5325);
WIRE 16 -1 (-7325 3325)(-7100 3325);
WIRE 16 -1 (-7325 4275)(-6900 4275);
WIRE 16 -1 (-2150 3300)(-1925 3300);
WIRE 16 -1 (-2150 3550)(-1725 3550);
WIRE 16 -1 (-2150 4250)(-1725 4250);
WIRE 16 -1 (-2150 3200)(-1725 3200);
WIRE 16 -1 (-2150 5300)(-1725 5300);
WIRE 16 -1 (-2150 4950)(-1725 4950);
WIRE 16 -1 (-7325 5675)(-6900 5675);
WIRE 16 -1 (-7325 3575)(-6900 3575);
WIRE 16 -1 (-7325 3675)(-7100 3675);
WIRE 16 -1 (-7325 3925)(-6900 3925);
WIRE 16 -1 (-7000 2050)(-6575 2050);
WIRE 16 -1 (-7150 2050)(-7750 2050);
WIRE 16 -1 (-7150 2000)(-8000 2000);
WIRE 16 -1 (-7000 1800)(-6375 1800);
WIRE 16 -1 (-7000 1850)(-6575 1850);
WIRE 16 -1 (-7000 1650)(-6575 1650);
WIRE 16 -1 (-7000 1600)(-6375 1600);
WIRE 16 -1 (-7000 1400)(-6375 1400);
WIRE 16 -1 (-7000 1450)(-6575 1450);
WIRE 16 -1 (-7000 1250)(-6575 1250);
WIRE 16 -1 (-7000 1200)(-6375 1200);
WIRE 16 -1 (-7000 1050)(-6575 1050);
WIRE 16 -1 (-7000 1000)(-6375 1000);
WIRE 16 -1 (-7000 850)(-6575 850);
WIRE 16 -1 (-7000 800)(-6375 800);
WIRE 16 -1 (-7000 650)(-6575 650);
WIRE 16 -1 (-7000 600)(-6375 600);
WIRE 16 -1 (-7150 1850)(-7750 1850);
WIRE 16 -1 (-7150 1650)(-7750 1650);
WIRE 16 -1 (-7150 1800)(-8000 1800);
WIRE 16 -1 (-7150 1600)(-8000 1600);
WIRE 16 -1 (-7150 1450)(-7750 1450);
WIRE 16 -1 (-7150 1250)(-7750 1250);
WIRE 16 -1 (-7150 1050)(-7750 1050);
WIRE 16 -1 (-7150 1000)(-8000 1000);
WIRE 16 -1 (-7150 1200)(-8000 1200);
WIRE 16 -1 (-7150 1400)(-8000 1400);
WIRE 16 -1 (-7150 850)(-7750 850);
WIRE 16 -1 (-7150 650)(-7750 650);
WIRE 16 -1 (-7150 800)(-8000 800);
WIRE 16 -1 (-7150 600)(-8000 600);
WIRE 16 -1 (-2400 2050)(-1975 2050);
WIRE 16 -1 (-2400 2000)(-1775 2000);
WIRE 16 -1 (-2400 1850)(-1975 1850);
WIRE 16 -1 (-2550 2050)(-3150 2050);
WIRE 16 -1 (-2550 1850)(-3150 1850);
WIRE 16 -1 (-2400 1800)(-1775 1800);
WIRE 16 -1 (-2400 1600)(-1775 1600);
WIRE 16 -1 (-2400 1650)(-1975 1650);
WIRE 16 -1 (-2400 1400)(-1775 1400);
WIRE 16 -1 (-2400 1450)(-1975 1450);
WIRE 16 -1 (-2400 1250)(-1975 1250);
WIRE 16 -1 (-2400 1200)(-1775 1200);
WIRE 16 -1 (-2400 1050)(-1975 1050);
WIRE 16 -1 (-2400 800)(-1775 800);
WIRE 16 -1 (-2400 850)(-1975 850);
WIRE 16 -1 (-2400 1000)(-1775 1000);
WIRE 16 -1 (-2550 1650)(-3150 1650);
WIRE 16 -1 (-2550 1450)(-3150 1450);
WIRE 16 -1 (-2550 1050)(-3150 1050);
WIRE 16 -1 (-2550 1250)(-3150 1250);
WIRE 16 -1 (-2550 850)(-3150 850);
WIRE 16 -1 (-2550 2000)(-3400 2000);
WIRE 16 -1 (-2550 1800)(-3400 1800);
WIRE 16 -1 (-2550 1600)(-3400 1600);
WIRE 16 -1 (-2550 1400)(-3400 1400);
WIRE 16 -1 (-2550 1200)(-3400 1200);
WIRE 16 -1 (-2550 800)(-3400 800);
WIRE 16 -1 (-2550 1000)(-3400 1000);
WIRE 16 -1 (-2400 650)(-1975 650);
WIRE 16 -1 (-2400 600)(-1775 600);
WIRE 16 -1 (-2550 650)(-3150 650);
WIRE 16 -1 (-2550 600)(-3400 600);
WIRE 16 -1 (-7000 2000)(-6375 2000);
FORCENOTE
RETIMER TO EXAMAX
(-8675 2875) 0;
DISPLAY LEFT (-8675 2875);
DISPLAY 3.148936 (-8675 2875);
FORCENOTE
RETIMER TO EXAMAX
(-3675 2850) 0;
DISPLAY LEFT (-3675 2850);
DISPLAY 3.148936 (-3675 2850);
FORCENOTE
P5E_CPU0_P3_TX_BUF_DP/PD<0-15> LANE REVERSAL
(-9050 6425) 0;
DISPLAY LEFT (-9050 6425);
DISPLAY 1.595745 (-9050 6425);
QUIT
